G04 ================== begin FILE IDENTIFICATION RECORD ==================*
G04 Layout Name:  9054_F0T_PDB_BD_GPU_F_V04_1213_1550.brd*
G04 Film Name:    gnd3*
G04 File Format:  Gerber RS274X*
G04 File Origin:  Cadence Allegro 17.2-S081*
G04 Origin Date:  Wed Dec 28 10:19:02 2022*
G04 *
G04 Layer:  DRAWING FORMAT/TITLE_BLOCK_A*
G04 Layer:  PIN/SPECIAL_DRILL*
G04 Layer:  DRAWING FORMAT/TITLE_BLOCK*
G04 Layer:  VIA CLASS/GND3*
G04 Layer:  PIN/GND3*
G04 Layer:  MANUFACTURING/PHOTOPLOT_OUTLINE*
G04 Layer:  ETCH/GND3*
G04 Layer:  DRAWING FORMAT/TITLE_DATA_GND3*
G04 *
G04 Offset:    (0.00 0.00)*
G04 Mirror:    No*
G04 Mode:      Negative*
G04 Rotation:  0*
G04 FullContactRelief:  No*
G04 UndefLineWidth:     6.00*
G04 ================== end FILE IDENTIFICATION RECORD ====================*
%FSLAX25Y25*MOIN*%
%IR0*IPPOS*OFA0.00000B0.00000*MIA0B0*SFA1.00000B1.00000*%
%ADD17C,.03*%
%ADD47C,.061*%
%ADD20C,.07*%
%ADD42C,.026*%
%ADD19C,.07*%
%AMMACRO15*
4,1,36,0.0,.01,
-.001736,.009848,
-.00342,.009397,
-.005,.00866,
-.006428,.00766,
-.00766,.006428,
-.00866,.005,
-.009397,.00342,
-.009848,.001736,
-.01,0.0,
-.009848,-.001736,
-.009397,-.00342,
-.00866,-.005,
-.00766,-.006428,
-.006428,-.00766,
-.005,-.00866,
-.00342,-.009397,
-.001736,-.009848,
0.0,-.01,
.001736,-.009848,
.00342,-.009397,
.005,-.00866,
.006428,-.00766,
.00766,-.006428,
.00866,-.005,
.009397,-.00342,
.009848,-.001736,
.01,0.0,
.009848,.001736,
.009397,.00342,
.00866,.005,
.00766,.006428,
.006428,.00766,
.005,.00866,
.00342,.009397,
.001736,.009848,
0.0,.01,
0.0*
%
%ADD15MACRO15*%
%AMMACRO29*
4,1,36,.0025,0.0,
.002462,.000434,
.002349,.000855,
.002165,.00125,
.001915,.001607,
.001607,.001915,
.00125,.002165,
.000855,.002349,
.000434,.002462,
0.0,.0025,
-.000434,.002462,
-.000855,.002349,
-.00125,.002165,
-.001607,.001915,
-.001915,.001607,
-.002165,.00125,
-.002349,.000855,
-.002462,.000434,
-.0025,0.0,
-.002462,-.000434,
-.002349,-.000855,
-.002165,-.00125,
-.001915,-.001607,
-.001607,-.001915,
-.00125,-.002165,
-.000855,-.002349,
-.000434,-.002462,
0.0,-.0025,
.000434,-.002462,
.000855,-.002349,
.00125,-.002165,
.001607,-.001915,
.001915,-.001607,
.002165,-.00125,
.002349,-.000855,
.002462,-.000434,
.0025,0.0,
270.*
%
%ADD29MACRO29*%
%AMMACRO28*
4,1,36,.0025,0.0,
.002462,.000434,
.002349,.000855,
.002165,.00125,
.001915,.001607,
.001607,.001915,
.00125,.002165,
.000855,.002349,
.000434,.002462,
0.0,.0025,
-.000434,.002462,
-.000855,.002349,
-.00125,.002165,
-.001607,.001915,
-.001915,.001607,
-.002165,.00125,
-.002349,.000855,
-.002462,.000434,
-.0025,0.0,
-.002462,-.000434,
-.002349,-.000855,
-.002165,-.00125,
-.001915,-.001607,
-.001607,-.001915,
-.00125,-.002165,
-.000855,-.002349,
-.000434,-.002462,
0.0,-.0025,
.000434,-.002462,
.000855,-.002349,
.00125,-.002165,
.001607,-.001915,
.001915,-.001607,
.002165,-.00125,
.002349,-.000855,
.002462,-.000434,
.0025,0.0,
180.*
%
%ADD28MACRO28*%
%ADD37C,.066*%
%ADD34C,.06015*%
%ADD31C,.087*%
%AMMACRO21*
4,1,36,0.0,.0135,
-.002344,.013295,
-.004617,.012686,
-.00675,.011691,
-.008678,.010342,
-.010342,.008678,
-.011691,.00675,
-.012686,.004617,
-.013295,.002344,
-.0135,0.0,
-.013295,-.002344,
-.012686,-.004617,
-.011691,-.00675,
-.010342,-.008678,
-.008678,-.010342,
-.00675,-.011691,
-.004617,-.012686,
-.002344,-.013295,
0.0,-.0135,
.002344,-.013295,
.004617,-.012686,
.00675,-.011691,
.008678,-.010342,
.010342,-.008678,
.011691,-.00675,
.012686,-.004617,
.013295,-.002344,
.0135,0.0,
.013295,.002344,
.012686,.004617,
.011691,.00675,
.010342,.008678,
.008678,.010342,
.00675,.011691,
.004617,.012686,
.002344,.013295,
0.0,.0135,
0.0*
%
%ADD21MACRO21*%
%AMMACRO43*
4,1,17,.09027,.06198,
.099661,.045363,
.106024,.027368,
.109166,.008541,
.108991,-.010545,
.105504,-.029311,
.098811,-.047186,
.09027,-.06198,
.0953,-.06701,
.105488,-.049443,
.112471,-.030374,
.116037,-.010382,
.116077,.009925,
.11259,.029931,
.105682,.049027,
.095563,.066634,
.0953,.06701,
.09027,.06198,
90.*
4,1,17,.06198,-.09027,
.045363,-.099661,
.027368,-.106024,
.008541,-.109166,
-.010545,-.108991,
-.029311,-.105504,
-.047186,-.098811,
-.06198,-.09027,
-.06701,-.0953,
-.049443,-.105488,
-.030374,-.112471,
-.010382,-.116037,
.009925,-.116077,
.029931,-.11259,
.049027,-.105682,
.066634,-.095563,
.06701,-.0953,
.06198,-.09027,
90.*
4,1,17,-.09027,-.06198,
-.099661,-.045363,
-.106024,-.027368,
-.109166,-.008541,
-.108991,.010545,
-.105504,.029311,
-.098811,.047186,
-.09027,.06198,
-.0953,.06701,
-.105488,.049443,
-.112471,.030374,
-.116037,.010382,
-.116077,-.009925,
-.11259,-.029931,
-.105682,-.049027,
-.095563,-.066634,
-.0953,-.06701,
-.09027,-.06198,
90.*
4,1,17,-.06198,.09027,
-.045363,.099661,
-.027368,.106024,
-.008541,.109166,
.010545,.108991,
.029311,.105504,
.047186,.098811,
.06198,.09027,
.06701,.0953,
.049443,.105488,
.030374,.112471,
.010382,.116037,
-.009925,.116077,
-.029931,.11259,
-.049027,.105682,
-.066634,.095563,
-.06701,.0953,
-.06198,.09027,
90.*
%
%ADD43MACRO43*%
%ADD18C,.04952*%
%AMMACRO45*
4,1,15,.02475,.01414,
.026829,.009627,
.028094,.004822,
.028504,-.000129,
.028049,-.005077,
.026741,-.009871,
.02475,-.01414,
.02984,-.01923,
.032726,-.013756,
.034617,-.007864,
.035457,-.001734,
.03522,.00445,
.033912,.010498,
.031574,.016227,
.02984,.01923,
.02475,.01414,
90.*
4,1,15,.01414,-.02475,
.009627,-.026829,
.004822,-.028094,
-.000129,-.028504,
-.005077,-.028049,
-.009871,-.026741,
-.01414,-.02475,
-.01923,-.02984,
-.013756,-.032726,
-.007864,-.034617,
-.001734,-.035457,
.00445,-.03522,
.010498,-.033912,
.016227,-.031574,
.01923,-.02984,
.01414,-.02475,
90.*
4,1,15,-.02475,-.01414,
-.026829,-.009627,
-.028094,-.004822,
-.028504,.000129,
-.028049,.005077,
-.026741,.009871,
-.02475,.01414,
-.02984,.01923,
-.032726,.013756,
-.034617,.007864,
-.035457,.001734,
-.03522,-.00445,
-.033912,-.010498,
-.031574,-.016227,
-.02984,-.01923,
-.02475,-.01414,
90.*
4,1,15,-.01414,.02475,
-.009627,.026829,
-.004822,.028094,
.000129,.028504,
.005077,.028049,
.009871,.026741,
.01414,.02475,
.01923,.02984,
.013756,.032726,
.007864,.034617,
.001734,.035457,
-.00445,.03522,
-.010498,.033912,
-.016227,.031574,
-.01923,.02984,
-.01414,.02475,
90.*
%
%ADD45MACRO45*%
%AMMACRO38*
4,1,16,.02657,.01597,
.02894,.011114,
.03043,.005919,
.030995,.000545,
.030619,-.004845,
.029313,-.010088,
.027115,-.015025,
.02657,-.01597,
.03164,-.02104,
.034813,-.015226,
.036928,-.00895,
.037921,-.002401,
.037762,.00422,
.036455,.010713,
.034041,.016881,
.03164,.02104,
.02657,.01597,
90.*
4,1,16,.01597,-.02657,
.011114,-.02894,
.005919,-.03043,
.000545,-.030995,
-.004845,-.030619,
-.010088,-.029313,
-.015025,-.027115,
-.01597,-.02657,
-.02104,-.03164,
-.015226,-.034813,
-.00895,-.036928,
-.002401,-.037921,
.00422,-.037762,
.010713,-.036455,
.016881,-.034041,
.02104,-.03164,
.01597,-.02657,
90.*
4,1,16,-.02657,-.01597,
-.02894,-.011114,
-.03043,-.005919,
-.030995,-.000545,
-.030619,.004845,
-.029313,.010088,
-.027115,.015025,
-.02657,.01597,
-.03164,.02104,
-.034813,.015226,
-.036928,.00895,
-.037921,.002401,
-.037762,-.00422,
-.036455,-.010713,
-.034041,-.016881,
-.03164,-.02104,
-.02657,-.01597,
90.*
4,1,16,-.01597,.02657,
-.011114,.02894,
-.005919,.03043,
-.000545,.030995,
.004845,.030619,
.010088,.029313,
.015025,.027115,
.01597,.02657,
.02104,.03164,
.015226,.034813,
.00895,.036928,
.002401,.037921,
-.00422,.037762,
-.010713,.036455,
-.016881,.034041,
-.02104,.03164,
-.01597,.02657,
90.*
%
%ADD38MACRO38*%
%AMMACRO41*
4,1,15,.03682,.01914,
.039584,.012455,
.041146,.005393,
.041457,-.001834,
.040509,-.009005,
.03833,-.015903,
.03682,-.01914,
.04197,-.0243,
.045552,-.016643,
.04775,-.00848,
.048497,-.000059,
.047771,.008363,
.045593,.016531,
.042029,.024197,
.04197,.0243,
.03682,.01914,
90.*
4,1,15,.01914,-.03682,
.012455,-.039584,
.005393,-.041146,
-.001834,-.041457,
-.009005,-.040509,
-.015903,-.03833,
-.01914,-.03682,
-.0243,-.04197,
-.016643,-.045552,
-.00848,-.04775,
-.000059,-.048497,
.008363,-.047771,
.016531,-.045593,
.024197,-.042029,
.0243,-.04197,
.01914,-.03682,
90.*
4,1,15,-.03682,-.01914,
-.039584,-.012455,
-.041146,-.005393,
-.041457,.001834,
-.040509,.009005,
-.03833,.015903,
-.03682,.01914,
-.04197,.0243,
-.045552,.016643,
-.04775,.00848,
-.048497,.000059,
-.047771,-.008363,
-.045593,-.016531,
-.042029,-.024197,
-.04197,-.0243,
-.03682,-.01914,
90.*
4,1,15,-.01914,.03682,
-.012455,.039584,
-.005393,.041146,
.001834,.041457,
.009005,.040509,
.015903,.03833,
.01914,.03682,
.0243,.04197,
.016643,.045552,
.00848,.04775,
.000059,.048497,
-.008363,.047771,
-.016531,.045593,
-.024197,.042029,
-.0243,.04197,
-.01914,.03682,
90.*
%
%ADD41MACRO41*%
%AMMACRO40*
4,1,15,-.03682,.01914,
-.039584,.012455,
-.041146,.005393,
-.041457,-.001834,
-.040509,-.009005,
-.03833,-.015903,
-.03682,-.01914,
-.04197,-.0243,
-.045552,-.016643,
-.04775,-.00848,
-.048497,-.000059,
-.047771,.008363,
-.045593,.016531,
-.042029,.024197,
-.04197,.0243,
-.03682,.01914,
90.*
4,1,15,-.01914,-.03682,
-.012455,-.039584,
-.005393,-.041146,
.001834,-.041457,
.009005,-.040509,
.015903,-.03833,
.01914,-.03682,
.0243,-.04197,
.016643,-.045552,
.00848,-.04775,
.000059,-.048497,
-.008363,-.047771,
-.016531,-.045593,
-.024197,-.042029,
-.0243,-.04197,
-.01914,-.03682,
90.*
4,1,15,.03682,-.01914,
.039584,-.012455,
.041146,-.005393,
.041457,.001834,
.040509,.009005,
.03833,.015903,
.03682,.01914,
.04197,.0243,
.045552,.016643,
.04775,.00848,
.048497,.000059,
.047771,-.008363,
.045593,-.016531,
.042029,-.024197,
.04197,-.0243,
.03682,-.01914,
90.*
4,1,15,.01914,.03682,
.012455,.039584,
.005393,.041146,
-.001834,.041457,
-.009005,.040509,
-.015903,.03833,
-.01914,.03682,
-.0243,.04197,
-.016643,.045552,
-.00848,.04775,
-.000059,.048497,
.008363,.047771,
.016531,.045593,
.024197,.042029,
.0243,.04197,
.01914,.03682,
90.*
%
%ADD40MACRO40*%
%ADD25C,.113*%
%AMMACRO14*
4,1,36,0.0,.005,
.000868,.004924,
.00171,.004698,
.0025,.00433,
.003214,.00383,
.00383,.003214,
.00433,.0025,
.004698,.00171,
.004924,.000868,
.005,0.0,
.004924,-.000868,
.004698,-.00171,
.00433,-.0025,
.00383,-.003214,
.003214,-.00383,
.0025,-.00433,
.00171,-.004698,
.000868,-.004924,
0.0,-.005,
-.000868,-.004924,
-.00171,-.004698,
-.0025,-.00433,
-.003214,-.00383,
-.00383,-.003214,
-.00433,-.0025,
-.004698,-.00171,
-.004924,-.000868,
-.005,0.0,
-.004924,.000868,
-.004698,.00171,
-.00433,.0025,
-.00383,.003214,
-.003214,.00383,
-.0025,.00433,
-.00171,.004698,
-.000868,.004924,
0.0,.005,
180.*
%
%ADD14MACRO14*%
%ADD27C,.115*%
%ADD46C,.116*%
%ADD10C,.125*%
%ADD23C,.155*%
%ADD35C,.256*%
%AMMACRO26*
4,1,36,0.0,.0135,
-.002344,.013295,
-.004617,.012686,
-.00675,.011691,
-.008678,.010342,
-.010342,.008678,
-.011691,.00675,
-.012686,.004617,
-.013295,.002344,
-.0135,0.0,
-.013295,-.002344,
-.012686,-.004617,
-.011691,-.00675,
-.010342,-.008678,
-.008678,-.010342,
-.00675,-.011691,
-.004617,-.012686,
-.002344,-.013295,
0.0,-.0135,
.002344,-.013295,
.004617,-.012686,
.00675,-.011691,
.008678,-.010342,
.010342,-.008678,
.011691,-.00675,
.012686,-.004617,
.013295,-.002344,
.0135,0.0,
.013295,.002344,
.012686,.004617,
.011691,.00675,
.010342,.008678,
.008678,.010342,
.00675,.011691,
.004617,.012686,
.002344,.013295,
0.0,.0135,
270.*
%
%ADD26MACRO26*%
%AMMACRO22*
4,1,36,0.0,.0135,
-.002344,.013295,
-.004617,.012686,
-.00675,.011691,
-.008678,.010342,
-.010342,.008678,
-.011691,.00675,
-.012686,.004617,
-.013295,.002344,
-.0135,0.0,
-.013295,-.002344,
-.012686,-.004617,
-.011691,-.00675,
-.010342,-.008678,
-.008678,-.010342,
-.00675,-.011691,
-.004617,-.012686,
-.002344,-.013295,
0.0,-.0135,
.002344,-.013295,
.004617,-.012686,
.00675,-.011691,
.008678,-.010342,
.010342,-.008678,
.011691,-.00675,
.012686,-.004617,
.013295,-.002344,
.0135,0.0,
.013295,.002344,
.012686,.004617,
.011691,.00675,
.010342,.008678,
.008678,.010342,
.00675,.011691,
.004617,.012686,
.002344,.013295,
0.0,.0135,
180.*
%
%ADD22MACRO22*%
%AMMACRO24*
4,1,36,.0025,0.0,
.002462,.000434,
.002349,.000855,
.002165,.00125,
.001915,.001607,
.001607,.001915,
.00125,.002165,
.000855,.002349,
.000434,.002462,
0.0,.0025,
-.000434,.002462,
-.000855,.002349,
-.00125,.002165,
-.001607,.001915,
-.001915,.001607,
-.002165,.00125,
-.002349,.000855,
-.002462,.000434,
-.0025,0.0,
-.002462,-.000434,
-.002349,-.000855,
-.002165,-.00125,
-.001915,-.001607,
-.001607,-.001915,
-.00125,-.002165,
-.000855,-.002349,
-.000434,-.002462,
0.0,-.0025,
.000434,-.002462,
.000855,-.002349,
.00125,-.002165,
.001607,-.001915,
.001915,-.001607,
.002165,-.00125,
.002349,-.000855,
.002462,-.000434,
.0025,0.0,
90.*
%
%ADD24MACRO24*%
%ADD36C,.187*%
%AMMACRO33*
4,1,36,0.0,.019,
-.003299,.018711,
-.006498,.017854,
-.0095,.016454,
-.012213,.014555,
-.014555,.012213,
-.016454,.0095,
-.017854,.006498,
-.018711,.003299,
-.019,0.0,
-.018711,-.003299,
-.017854,-.006498,
-.016454,-.0095,
-.014555,-.012213,
-.012213,-.014555,
-.0095,-.016454,
-.006498,-.017854,
-.003299,-.018711,
0.0,-.019,
.003299,-.018711,
.006498,-.017854,
.0095,-.016454,
.012213,-.014555,
.014555,-.012213,
.016454,-.0095,
.017854,-.006498,
.018711,-.003299,
.019,0.0,
.018711,.003299,
.017854,.006498,
.016454,.0095,
.014555,.012213,
.012213,.014555,
.0095,.016454,
.006498,.017854,
.003299,.018711,
0.0,.019,
180.*
%
%ADD33MACRO33*%
%AMMACRO11*
4,1,36,.0025,0.0,
.002462,.000434,
.002349,.000855,
.002165,.00125,
.001915,.001607,
.001607,.001915,
.00125,.002165,
.000855,.002349,
.000434,.002462,
0.0,.0025,
-.000434,.002462,
-.000855,.002349,
-.00125,.002165,
-.001607,.001915,
-.001915,.001607,
-.002165,.00125,
-.002349,.000855,
-.002462,.000434,
-.0025,0.0,
-.002462,-.000434,
-.002349,-.000855,
-.002165,-.00125,
-.001915,-.001607,
-.001607,-.001915,
-.00125,-.002165,
-.000855,-.002349,
-.000434,-.002462,
0.0,-.0025,
.000434,-.002462,
.000855,-.002349,
.00125,-.002165,
.001607,-.001915,
.001915,-.001607,
.002165,-.00125,
.002349,-.000855,
.002462,-.000434,
.0025,0.0,
0.0*
%
%ADD11MACRO11*%
%ADD16C,.188*%
%AMMACRO44*
4,1,21,-.0075,-.06379,
-.0075,-.0709,
-.015443,-.068892,
-.022917,-.065536,
-.029695,-.060932,
-.03557,-.055222,
-.040364,-.048578,
-.043932,-.041203,
-.046165,-.03332,
-.046995,-.025169,
-.047,-.0245,
-.047,-.0075,
-.04,-.0075,
-.04,-.0245,
-.039392,-.031446,
-.037588,-.038181,
-.034641,-.0445,
-.030642,-.050211,
-.025712,-.055141,
-.02,-.05914,
-.013681,-.062087,
-.0075,-.06379,
90.*
4,1,21,.0075,-.0709,
.0075,-.06379,
.014209,-.061891,
.020486,-.058856,
.02614,-.054776,
.031001,-.049777,
.034919,-.04401,
.037776,-.03765,
.039486,-.030891,
.04,-.0245,
.04,-.0075,
.047,-.0075,
.047,-.0245,
.046286,-.032662,
.044165,-.040576,
.040703,-.048001,
.036003,-.054713,
.03021,-.060506,
.023499,-.065205,
.016073,-.068668,
.008159,-.070789,
.0075,-.0709,
90.*
4,1,21,-.0075,.0709,
-.0075,.06379,
-.014209,.061891,
-.020486,.058856,
-.02614,.054776,
-.031001,.049777,
-.034919,.04401,
-.037776,.03765,
-.039486,.030891,
-.04,.0245,
-.04,.0075,
-.047,.0075,
-.047,.0245,
-.046286,.032662,
-.044165,.040576,
-.040703,.048001,
-.036003,.054713,
-.03021,.060506,
-.023499,.065205,
-.016073,.068668,
-.008159,.070789,
-.0075,.0709,
90.*
4,1,21,.0075,.06379,
.0075,.0709,
.015443,.068892,
.022917,.065536,
.029695,.060932,
.03557,.055222,
.040364,.048578,
.043932,.041203,
.046165,.03332,
.046995,.025169,
.047,.0245,
.047,.0075,
.04,.0075,
.04,.0245,
.039392,.031446,
.037588,.038181,
.034641,.0445,
.030642,.050211,
.025712,.055141,
.02,.05914,
.013681,.062087,
.0075,.06379,
90.*
%
%ADD44MACRO44*%
%AMMACRO39*
4,1,16,.02657,.01597,
.02894,.011114,
.03043,.005919,
.030995,.000545,
.030619,-.004845,
.029313,-.010088,
.027115,-.015025,
.02657,-.01597,
.03164,-.02104,
.034813,-.015226,
.036928,-.00895,
.037921,-.002401,
.037762,.00422,
.036455,.010713,
.034041,.016881,
.03164,.02104,
.02657,.01597,
270.*
4,1,16,.01597,-.02657,
.011114,-.02894,
.005919,-.03043,
.000545,-.030995,
-.004845,-.030619,
-.010088,-.029313,
-.015025,-.027115,
-.01597,-.02657,
-.02104,-.03164,
-.015226,-.034813,
-.00895,-.036928,
-.002401,-.037921,
.00422,-.037762,
.010713,-.036455,
.016881,-.034041,
.02104,-.03164,
.01597,-.02657,
270.*
4,1,16,-.02657,-.01597,
-.02894,-.011114,
-.03043,-.005919,
-.030995,-.000545,
-.030619,.004845,
-.029313,.010088,
-.027115,.015025,
-.02657,.01597,
-.03164,.02104,
-.034813,.015226,
-.036928,.00895,
-.037921,.002401,
-.037762,-.00422,
-.036455,-.010713,
-.034041,-.016881,
-.03164,-.02104,
-.02657,-.01597,
270.*
4,1,16,-.01597,.02657,
-.011114,.02894,
-.005919,.03043,
-.000545,.030995,
.004845,.030619,
.010088,.029313,
.015025,.027115,
.01597,.02657,
.02104,.03164,
.015226,.034813,
.00895,.036928,
.002401,.037921,
-.00422,.037762,
-.010713,.036455,
-.016881,.034041,
-.02104,.03164,
-.01597,.02657,
270.*
%
%ADD39MACRO39*%
%AMMACRO12*
4,1,18,.10783,.07955,
.120006,.059617,
.128535,.037873,
.133159,.014977,
.133736,-.008373,
.130251,-.031469,
.122807,-.053609,
.111633,-.074119,
.10783,-.07955,
.11284,-.08455,
.125808,-.063671,
.134953,-.040857,
.139997,-.016802,
.140788,.007763,
.137301,.032093,
.129642,.055447,
.118045,.077117,
.11284,.08455,
.10783,.07955,
180.*
4,1,18,.07955,-.10783,
.059617,-.120006,
.037873,-.128535,
.014977,-.133159,
-.008373,-.133736,
-.031469,-.130251,
-.053609,-.122807,
-.074119,-.111633,
-.07955,-.10783,
-.08455,-.11284,
-.063671,-.125808,
-.040857,-.134953,
-.016802,-.139997,
.007763,-.140788,
.032093,-.137301,
.055447,-.129642,
.077117,-.118045,
.08455,-.11284,
.07955,-.10783,
180.*
4,1,18,-.10783,-.07955,
-.120006,-.059617,
-.128535,-.037873,
-.133159,-.014977,
-.133736,.008373,
-.130251,.031469,
-.122807,.053609,
-.111633,.074119,
-.10783,.07955,
-.11284,.08455,
-.125808,.063671,
-.134953,.040857,
-.139997,.016802,
-.140788,-.007763,
-.137301,-.032093,
-.129642,-.055447,
-.118045,-.077117,
-.11284,-.08455,
-.10783,-.07955,
180.*
4,1,18,-.07955,.10783,
-.059617,.120006,
-.037873,.128535,
-.014977,.133159,
.008373,.133736,
.031469,.130251,
.053609,.122807,
.074119,.111633,
.07955,.10783,
.08455,.11284,
.063671,.125808,
.040857,.134953,
.016802,.139997,
-.007763,.140788,
-.032093,.137301,
-.055447,.129642,
-.077117,.118045,
-.08455,.11284,
-.07955,.10783,
180.*
%
%ADD12MACRO12*%
%AMMACRO30*
4,1,15,.03682,.01914,
.039584,.012455,
.041146,.005393,
.041457,-.001834,
.040509,-.009005,
.03833,-.015903,
.03682,-.01914,
.04197,-.0243,
.045552,-.016643,
.04775,-.00848,
.048497,-.000059,
.047771,.008363,
.045593,.016531,
.042029,.024197,
.04197,.0243,
.03682,.01914,
270.*
4,1,15,.01914,-.03682,
.012455,-.039584,
.005393,-.041146,
-.001834,-.041457,
-.009005,-.040509,
-.015903,-.03833,
-.01914,-.03682,
-.0243,-.04197,
-.016643,-.045552,
-.00848,-.04775,
-.000059,-.048497,
.008363,-.047771,
.016531,-.045593,
.024197,-.042029,
.0243,-.04197,
.01914,-.03682,
270.*
4,1,15,-.03682,-.01914,
-.039584,-.012455,
-.041146,-.005393,
-.041457,.001834,
-.040509,.009005,
-.03833,.015903,
-.03682,.01914,
-.04197,.0243,
-.045552,.016643,
-.04775,.00848,
-.048497,.000059,
-.047771,-.008363,
-.045593,-.016531,
-.042029,-.024197,
-.04197,-.0243,
-.03682,-.01914,
270.*
4,1,15,-.01914,.03682,
-.012455,.039584,
-.005393,.041146,
.001834,.041457,
.009005,.040509,
.015903,.03833,
.01914,.03682,
.0243,.04197,
.016643,.045552,
.00848,.04775,
.000059,.048497,
-.008363,.047771,
-.016531,.045593,
-.024197,.042029,
-.0243,.04197,
-.01914,.03682,
270.*
%
%ADD30MACRO30*%
%AMMACRO32*
4,1,15,-.03682,.01914,
-.039584,.012455,
-.041146,.005393,
-.041457,-.001834,
-.040509,-.009005,
-.03833,-.015903,
-.03682,-.01914,
-.04197,-.0243,
-.045552,-.016643,
-.04775,-.00848,
-.048497,-.000059,
-.047771,.008363,
-.045593,.016531,
-.042029,.024197,
-.04197,.0243,
-.03682,.01914,
270.*
4,1,15,-.01914,-.03682,
-.012455,-.039584,
-.005393,-.041146,
.001834,-.041457,
.009005,-.040509,
.015903,-.03833,
.01914,-.03682,
.0243,-.04197,
.016643,-.045552,
.00848,-.04775,
.000059,-.048497,
-.008363,-.047771,
-.016531,-.045593,
-.024197,-.042029,
-.0243,-.04197,
-.01914,-.03682,
270.*
4,1,15,.03682,-.01914,
.039584,-.012455,
.041146,-.005393,
.041457,.001834,
.040509,.009005,
.03833,.015903,
.03682,.01914,
.04197,.0243,
.045552,.016643,
.04775,.00848,
.048497,.000059,
.047771,-.008363,
.045593,-.016531,
.042029,-.024197,
.04197,-.0243,
.03682,-.01914,
270.*
4,1,15,.01914,.03682,
.012455,.039584,
.005393,.041146,
-.001834,.041457,
-.009005,.040509,
-.015903,.03833,
-.01914,.03682,
-.0243,.04197,
-.016643,.045552,
-.00848,.04775,
-.000059,.048497,
.008363,.047771,
.016531,.045593,
.024197,.042029,
.0243,.04197,
.01914,.03682,
270.*
%
%ADD32MACRO32*%
%ADD48C,.02*%
%ADD49C,.006*%
%ADD57C,.0801*%
%ADD56C,.07006*%
%ADD59C,.09558*%
%ADD60C,.11022*%
%ADD58C,.12006*%
%ADD55C,.11708*%
%ADD51C,.12608*%
%ADD54C,.13509*%
%ADD52C,.16506*%
%ADD50C,.28606*%
%ADD53C,.19806*%
G75*
%LPD*%
G75*
G36*
G01X-457143Y-1211429D02*
X4308572D01*
Y2242857D01*
X-457143D01*
Y-1211429D01*
G37*
%LPC*%
G75*
G36*
G01X1854331Y516776D02*
G02X1872012Y499095I-1J-17682D01*
G01Y85709D01*
G02X1854331Y68028I-17681J0D01*
G01X1751968D01*
G03X1730279Y46339I1J-21690D01*
G01Y19685D01*
G02X1712598Y2004I-17681J0D01*
G01X19685D01*
G02X2004Y19685I0J17681D01*
G01Y603543D01*
G02X19685Y621224I17681J0D01*
G01X102362D01*
G03X124051Y642913I0J21689D01*
G01Y656102D01*
G02X141732Y673783I17681J0D01*
G01X295276D01*
G02X312957Y656102I0J-17681D01*
G01Y634965D01*
G03X326698Y621224I14799J1058D01*
G01X328740D01*
G02X346421Y603543I0J-17681D01*
G01Y435039D01*
G03X377952Y403508I31532J1D01*
G01X1252385D01*
X1252389Y403512D01*
X1256109D01*
X1256113Y403508D01*
X1354331D01*
G03X1385862Y435039I0J31531D01*
G01Y603543D01*
G02X1403543Y621224I17681J0D01*
G01X1405512D01*
G03X1419327Y635039I0J13815D01*
G01Y656102D01*
G02X1437008Y673783I17681J0D01*
G01X1590551D01*
G02X1608232Y656102I0J-17681D01*
G01Y642913D01*
G03X1629921Y621224I21689J0D01*
G01X1712598D01*
G02X1730279Y603543I0J-17681D01*
G01Y538465D01*
G03X1751968Y516776I21690J0D01*
G01X1854331D01*
G37*
G36*
G01X1866142Y783851D02*
G02X1872016Y777977I0J-5874D01*
G01Y534528D01*
G02X1866142Y528654I-5874J0D01*
G01X1751968D01*
G02X1742157Y538465I1J9811D01*
G01Y603543D01*
G03X1712598Y633102I-29559J0D01*
G01X1640064D01*
G02X1630253Y642913I0J9811D01*
G01Y738607D01*
G03X1620379Y748481I-9874J0D01*
G01X1383858D01*
G03X1373984Y738607I0J-9874D01*
G01Y435039D01*
G02X1354331Y415386I-19653J0D01*
G01X1154764D01*
G02X1148890Y421260I0J5874D01*
G01Y479449D01*
G03X1135079Y493260I-13811J0D01*
G01X550827D01*
G03X537016Y479449I0J-13811D01*
G01Y421260D01*
G02X531142Y415386I-5874J0D01*
G01X377952D01*
G02X358299Y435039I0J19653D01*
G01Y738607D01*
G03X348425Y748481I-9874J0D01*
G01X111905D01*
G03X102031Y738607I0J-9874D01*
G01Y642913D01*
G02X92220Y633102I-9811J0D01*
G01X7874D01*
G02X2000Y638976I0J5874D01*
G01Y777977D01*
G02X7874Y783851I5874J0D01*
G01X1866142D01*
G37*
%LPD*%
G75*
G36*
G01X695332Y327292D02*
G02X696610Y327534I1279J-3260D01*
G01X696613D01*
G02Y320530I0J-3502D01*
G01X696610D01*
G02X695332Y320772I1J3502D01*
G03X695185I-73J-186D01*
G02X693907Y320530I-1279J3260D01*
G01X693904D01*
G02Y327534I0J3502D01*
G01X693907D01*
G02X695185Y327292I-1J-3502D01*
G03X695332I73J186D01*
G37*
G36*
G01X1320919Y197645D02*
G02X1320348Y197598I-572J3455D01*
G01X1320346D01*
G02X1323848Y201100I0J3502D01*
G02X1323142Y198991I-3503J0D01*
G03X1323527Y198355I319J-241D01*
G02X1324098Y198402I572J-3455D01*
G01X1324100D01*
G02X1320598Y194900I0J-3502D01*
G02X1321304Y197009I3503J0D01*
G03X1320919Y197645I-319J241D01*
G37*
G36*
G01Y153245D02*
G02X1320348Y153198I-572J3455D01*
G01X1320346D01*
G02X1323848Y156700I0J3502D01*
G02X1323142Y154591I-3503J0D01*
G03X1323527Y153955I319J-241D01*
G02X1324098Y154002I572J-3455D01*
G01X1324100D01*
G02X1320598Y150500I0J-3502D01*
G02X1321304Y152609I3503J0D01*
G03X1320919Y153245I-319J241D01*
G37*
G36*
G01X1563628Y664685D02*
Y664687D01*
G02X1568406Y669464I4778J-1D01*
G02X1572039Y667789I-1J-4779D01*
G03X1572191Y667719I152J130D01*
G01X1572495D01*
G03X1572647Y667789I0J200D01*
G02X1576280Y669464I3634J-3104D01*
G02X1581058Y664685I-1J-4779D01*
G02X1579384Y661052I-4779J0D01*
G03X1579314Y660900I130J-152D01*
G01Y660596D01*
G03X1579384Y660444I200J0D01*
G02Y653178I-3105J-3633D01*
G03X1579314Y653026I130J-152D01*
G01Y652722D01*
G03X1579384Y652570I200J0D01*
G02Y645304I-3105J-3633D01*
G03X1579314Y645152I130J-152D01*
G01Y644848D01*
G03X1579384Y644696I200J0D01*
G02Y637430I-3105J-3633D01*
G03X1579314Y637278I130J-152D01*
G01Y636974D01*
G03X1579384Y636822I200J0D01*
G02Y629556I-3105J-3633D01*
G03X1579314Y629404I130J-152D01*
G01Y629100D01*
G03X1579384Y628948I200J0D01*
G02Y621682I-3105J-3633D01*
G03X1579314Y621530I130J-152D01*
G01Y621226D01*
G03X1579384Y621074I200J0D01*
G02Y613808I-3105J-3633D01*
G03X1579314Y613656I130J-152D01*
G01Y613352D01*
G03X1579384Y613200I200J0D01*
G02Y605934I-3105J-3633D01*
G03X1579314Y605782I130J-152D01*
G01Y605478D01*
G03X1579384Y605326I200J0D01*
G02X1581058Y601693I-3105J-3633D01*
G01Y601691D01*
G02X1576280Y596914I-4778J1D01*
G02X1572647Y598589I1J4779D01*
G03X1572495Y598659I-152J-130D01*
G01X1572191D01*
G03X1572039Y598589I0J-200D01*
G02X1568406Y596914I-3634J3104D01*
G02X1563628Y601693I1J4779D01*
G02X1565302Y605326I4779J0D01*
G03X1565372Y605478I-130J152D01*
G01Y605782D01*
G03X1565302Y605934I-200J0D01*
G02Y613200I3105J3633D01*
G03X1565372Y613352I-130J152D01*
G01Y613656D01*
G03X1565302Y613808I-200J0D01*
G02Y621074I3105J3633D01*
G03X1565372Y621226I-130J152D01*
G01Y621530D01*
G03X1565302Y621682I-200J0D01*
G02Y628948I3105J3633D01*
G03X1565372Y629100I-130J152D01*
G01Y629404D01*
G03X1565302Y629556I-200J0D01*
G02Y636822I3105J3633D01*
G03X1565372Y636974I-130J152D01*
G01Y637278D01*
G03X1565302Y637430I-200J0D01*
G02Y644696I3105J3633D01*
G03X1565372Y644848I-130J152D01*
G01Y645152D01*
G03X1565302Y645304I-200J0D01*
G02Y652570I3105J3633D01*
G03X1565372Y652722I-130J152D01*
G01Y653026D01*
G03X1565302Y653178I-200J0D01*
G02Y660444I3105J3633D01*
G03X1565372Y660596I-130J152D01*
G01Y660900D01*
G03X1565302Y661052I-200J0D01*
G02X1563628Y664685I3105J3633D01*
G37*
G36*
G01X132524D02*
G02X137303Y669464I4779J0D01*
G02X140936Y667789I-1J-4779D01*
G03X141088Y667719I152J130D01*
G01X141392D01*
G03X141544Y667789I0J200D01*
G02X145177Y669464I3634J-3104D01*
G02X149956Y664685I0J-4779D01*
G02X148281Y661052I-4779J1D01*
G03X148211Y660900I130J-152D01*
G01Y660596D01*
G03X148281Y660444I200J0D01*
G02X149956Y656811I-3104J-3634D01*
G02X148281Y653178I-4779J1D01*
G03X148211Y653026I130J-152D01*
G01Y652722D01*
G03X148281Y652570I200J0D01*
G02X149956Y648937I-3104J-3634D01*
G02X148281Y645304I-4779J1D01*
G03X148211Y645152I130J-152D01*
G01Y644848D01*
G03X148281Y644696I200J0D01*
G02X149956Y641063I-3104J-3634D01*
G02X148281Y637430I-4779J1D01*
G03X148211Y637278I130J-152D01*
G01Y636974D01*
G03X148281Y636822I200J0D01*
G02X149956Y633189I-3104J-3634D01*
G02X148281Y629556I-4779J1D01*
G03X148211Y629404I130J-152D01*
G01Y629100D01*
G03X148281Y628948I200J0D01*
G02X149956Y625315I-3104J-3634D01*
G02X148281Y621682I-4779J1D01*
G03X148211Y621530I130J-152D01*
G01Y621226D01*
G03X148281Y621074I200J0D01*
G02X149956Y617441I-3104J-3634D01*
G02X148281Y613808I-4779J1D01*
G03X148211Y613656I130J-152D01*
G01Y613352D01*
G03X148281Y613200I200J0D01*
G02X149956Y609567I-3104J-3634D01*
G02X148281Y605934I-4779J1D01*
G03X148211Y605782I130J-152D01*
G01Y605478D01*
G03X148281Y605326I200J0D01*
G02X149956Y601693I-3104J-3634D01*
G02X145177Y596914I-4779J0D01*
G02X141544Y598589I1J4779D01*
G03X141392Y598659I-152J-130D01*
G01X141088D01*
G03X140936Y598589I0J-200D01*
G02X137303Y596914I-3634J3104D01*
G02X132524Y601693I0J4779D01*
G02X134199Y605326I4779J-1D01*
G03X134269Y605478I-130J152D01*
G01Y605782D01*
G03X134199Y605934I-200J0D01*
G02X132524Y609567I3104J3634D01*
G02X134199Y613200I4779J-1D01*
G03X134269Y613352I-130J152D01*
G01Y613656D01*
G03X134199Y613808I-200J0D01*
G02X132524Y617441I3104J3634D01*
G02X134199Y621074I4779J-1D01*
G03X134269Y621226I-130J152D01*
G01Y621530D01*
G03X134199Y621682I-200J0D01*
G02X132524Y625315I3104J3634D01*
G02X134199Y628948I4779J-1D01*
G03X134269Y629100I-130J152D01*
G01Y629404D01*
G03X134199Y629556I-200J0D01*
G02X132524Y633189I3104J3634D01*
G02X134199Y636822I4779J-1D01*
G03X134269Y636974I-130J152D01*
G01Y637278D01*
G03X134199Y637430I-200J0D01*
G02X132524Y641063I3104J3634D01*
G02X134199Y644696I4779J-1D01*
G03X134269Y644848I-130J152D01*
G01Y645152D01*
G03X134199Y645304I-200J0D01*
G02X132524Y648937I3104J3634D01*
G02X134199Y652570I4779J-1D01*
G03X134269Y652722I-130J152D01*
G01Y653026D01*
G03X134199Y653178I-200J0D01*
G02X132524Y656811I3104J3634D01*
G02X134199Y660444I4779J-1D01*
G03X134269Y660596I-130J152D01*
G01Y660900D01*
G03X134199Y661052I-200J0D01*
G02X132524Y664685I3104J3634D01*
G37*
G36*
G01X1530076Y638108D02*
X1530067Y638055D01*
X1530104Y637954D01*
X1530455Y637664D01*
X1530559Y637646D01*
X1530610Y637665D01*
G02X1532283Y637968I1675J-4476D01*
G02X1535916Y636293I-1J-4779D01*
G03X1536068Y636223I152J130D01*
G01X1536372D01*
G03X1536524Y636293I0J200D01*
G02X1540157Y637968I3634J-3104D01*
G02X1544936Y633189I0J-4779D01*
G02X1543261Y629556I-4779J1D01*
G03X1543191Y629404I130J-152D01*
G01Y629100D01*
G03X1543261Y628948I200J0D01*
G02X1544936Y625315I-3104J-3634D01*
G02X1543261Y621682I-4779J1D01*
G03X1543191Y621530I130J-152D01*
G01Y621226D01*
G03X1543261Y621074I200J0D01*
G02X1544936Y617441I-3104J-3634D01*
G02X1540157Y612662I-4779J0D01*
G02X1536524Y614337I1J4779D01*
G03X1536372Y614407I-152J-130D01*
G01X1536068D01*
G03X1535916Y614337I0J-200D01*
G02X1532283Y612662I-3634J3104D01*
G02X1527504Y617441I0J4779D01*
G02X1529179Y621074I4779J-1D01*
G03X1529249Y621226I-130J152D01*
G01Y621530D01*
G03X1529179Y621682I-200J0D01*
G02X1527504Y625315I3104J3634D01*
G02X1529179Y628948I4779J-1D01*
G03X1529249Y629100I-130J152D01*
G01Y629404D01*
G03X1529179Y629556I-200J0D01*
G02X1527504Y633189I3104J3634D01*
G02X1527518Y633540I4778J-15D01*
G01Y633542D01*
G03X1527431Y633722I-200J15D01*
G01X1527143Y633916D01*
G03X1526943Y633931I-113J-165D01*
G01X1526942Y633930D01*
G02X1521876I-2533J5164D01*
G01X1521875Y633931D01*
G03X1521675Y633916I-87J-180D01*
G01X1521387Y633722D01*
G03X1521300Y633542I113J-165D01*
G01Y633541D01*
G02X1521314Y633189I-4764J-366D01*
G02X1519639Y629556I-4779J1D01*
G03X1519569Y629404I130J-152D01*
G01Y629100D01*
G03X1519639Y628948I200J0D01*
G02X1521314Y625315I-3104J-3634D01*
G02X1519639Y621682I-4779J1D01*
G03X1519569Y621530I130J-152D01*
G01Y621226D01*
G03X1519639Y621074I200J0D01*
G02X1521314Y617441I-3104J-3634D01*
G02X1516535Y612662I-4779J0D01*
G02X1512902Y614337I1J4779D01*
G03X1512750Y614407I-152J-130D01*
G01X1512446D01*
G03X1512294Y614337I0J-200D01*
G02X1508661Y612662I-3634J3104D01*
G02X1503882Y617441I0J4779D01*
G02X1505557Y621074I4779J-1D01*
G03X1505627Y621226I-130J152D01*
G01Y621530D01*
G03X1505557Y621682I-200J0D01*
G02X1503882Y625315I3104J3634D01*
G02X1505557Y628948I4779J-1D01*
G03X1505627Y629100I-130J152D01*
G01Y629404D01*
G03X1505557Y629556I-200J0D01*
G02X1503882Y633189I3104J3634D01*
G02X1508661Y637968I4779J0D01*
G02X1512294Y636293I-1J-4779D01*
G03X1512446Y636223I152J130D01*
G01X1512750D01*
G03X1512902Y636293I0J200D01*
G02X1516535Y637968I3634J-3104D01*
G02X1518208Y637665I-2J-4779D01*
G01X1518259Y637646D01*
X1518363Y637664D01*
X1518714Y637954D01*
X1518751Y638055D01*
X1518742Y638108D01*
G02X1530076I5667J986D01*
G37*
G36*
G01X213541D02*
X213532Y638055D01*
X213569Y637954D01*
X213920Y637664D01*
X214024Y637646D01*
X214075Y637665D01*
G02X215748Y637968I1675J-4476D01*
G02X219381Y636293I-1J-4779D01*
G03X219533Y636223I152J130D01*
G01X219837D01*
G03X219989Y636293I0J200D01*
G02X223622Y637968I3634J-3104D01*
G02X228400Y633189I-1J-4779D01*
G02X226726Y629556I-4779J0D01*
G03X226656Y629404I130J-152D01*
G01Y629100D01*
G03X226726Y628948I200J0D01*
G02Y621682I-3105J-3633D01*
G03X226656Y621530I130J-152D01*
G01Y621226D01*
G03X226726Y621074I200J0D01*
G02X228400Y617441I-3105J-3633D01*
G01Y617439D01*
G02X223622Y612662I-4778J1D01*
G02X219989Y614337I1J4779D01*
G03X219837Y614407I-152J-130D01*
G01X219533D01*
G03X219381Y614337I0J-200D01*
G02X215748Y612662I-3634J3104D01*
G02X210970Y617441I1J4779D01*
G02X212644Y621074I4779J0D01*
G03X212714Y621226I-130J152D01*
G01Y621530D01*
G03X212644Y621682I-200J0D01*
G02Y628948I3105J3633D01*
G03X212714Y629100I-130J152D01*
G01Y629404D01*
G03X212644Y629556I-200J0D01*
G02X210970Y633189I3105J3633D01*
G02X210983Y633541I4778J0D01*
G01Y633542D01*
G03X210896Y633722I-200J15D01*
G01X210608Y633916D01*
G03X210408Y633931I-113J-165D01*
G01X210407Y633930D01*
G02X205341I-2533J5164D01*
G01X205340Y633931D01*
G03X205140Y633916I-87J-180D01*
G01X204852Y633722D01*
G03X204765Y633542I113J-165D01*
G01Y633541D01*
G02X204778Y633189I-4765J-352D01*
G02X203104Y629556I-4779J0D01*
G03X203034Y629404I130J-152D01*
G01Y629100D01*
G03X203104Y628948I200J0D01*
G02Y621682I-3105J-3633D01*
G03X203034Y621530I130J-152D01*
G01Y621226D01*
G03X203104Y621074I200J0D01*
G02X204778Y617441I-3105J-3633D01*
G01Y617439D01*
G02X200000Y612662I-4778J1D01*
G02X196367Y614337I1J4779D01*
G03X196215Y614407I-152J-130D01*
G01X195911D01*
G03X195759Y614337I0J-200D01*
G02X192126Y612662I-3634J3104D01*
G02X187348Y617441I1J4779D01*
G02X189022Y621074I4779J0D01*
G03X189092Y621226I-130J152D01*
G01Y621530D01*
G03X189022Y621682I-200J0D01*
G02Y628948I3105J3633D01*
G03X189092Y629100I-130J152D01*
G01Y629404D01*
G03X189022Y629556I-200J0D01*
G02X187348Y633189I3105J3633D01*
G01Y633191D01*
G02X192126Y637968I4778J-1D01*
G02X195759Y636293I-1J-4779D01*
G03X195911Y636223I152J130D01*
G01X196215D01*
G03X196367Y636293I0J200D01*
G02X200000Y637968I3634J-3104D01*
G02X201673Y637665I-2J-4779D01*
G01X201724Y637646D01*
X201828Y637664D01*
X202179Y637954D01*
X202216Y638055D01*
X202207Y638108D01*
G02X213541I5667J986D01*
G37*
G36*
G01X1476378Y637968D02*
G02X1480011Y636293I-1J-4779D01*
G03X1480163Y636223I152J130D01*
G01X1480467D01*
G03X1480619Y636293I0J200D01*
G02X1484252Y637968I3634J-3104D01*
G02X1489030Y633189I-1J-4779D01*
G02X1487356Y629556I-4779J0D01*
G03X1487286Y629404I130J-152D01*
G01Y629100D01*
G03X1487356Y628948I200J0D01*
G02Y621682I-3105J-3633D01*
G03X1487286Y621530I130J-152D01*
G01Y621226D01*
G03X1487356Y621074I200J0D01*
G02X1489030Y617441I-3105J-3633D01*
G01Y617439D01*
G02X1484252Y612662I-4778J1D01*
G02X1480619Y614337I1J4779D01*
G03X1480467Y614407I-152J-130D01*
G01X1480163D01*
G03X1480011Y614337I0J-200D01*
G02X1476378Y612662I-3634J3104D01*
G02X1471600Y617441I1J4779D01*
G02X1473274Y621074I4779J0D01*
G03X1473344Y621226I-130J152D01*
G01Y621530D01*
G03X1473274Y621682I-200J0D01*
G02X1472062Y623263I3103J3634D01*
G01X1472044Y623301D01*
X1471981Y623356D01*
X1471657Y623454D01*
G03X1471497Y623435I-58J-191D01*
G02X1465511I-2993J5030D01*
G03X1465351Y623454I-102J-172D01*
G01X1465027Y623356D01*
X1464964Y623301D01*
X1464946Y623263D01*
G02X1463734Y621682I-4315J2053D01*
G03X1463664Y621530I130J-152D01*
G01Y621226D01*
G03X1463734Y621074I200J0D01*
G02X1465408Y617441I-3105J-3633D01*
G01Y617439D01*
G02X1460630Y612662I-4778J1D01*
G02X1456997Y614337I1J4779D01*
G03X1456845Y614407I-152J-130D01*
G01X1456541D01*
G03X1456389Y614337I0J-200D01*
G02X1452756Y612662I-3634J3104D01*
G02X1447978Y617441I1J4779D01*
G02X1449652Y621074I4779J0D01*
G03X1449722Y621226I-130J152D01*
G01Y621530D01*
G03X1449652Y621682I-200J0D01*
G02Y628948I3105J3633D01*
G03X1449722Y629100I-130J152D01*
G01Y629404D01*
G03X1449652Y629556I-200J0D01*
G02X1447978Y633189I3105J3633D01*
G01Y633191D01*
G02X1452756Y637968I4778J-1D01*
G02X1456389Y636293I-1J-4779D01*
G03X1456541Y636223I152J130D01*
G01X1456845D01*
G03X1456997Y636293I0J200D01*
G02X1460630Y637968I3634J-3104D01*
G02X1465339Y634002I0J-4779D01*
G03X1465445Y633857I197J33D01*
G01X1465731Y633712D01*
G03X1465910Y633711I90J178D01*
G02X1471098I2594J-5246D01*
G01X1471141Y633690D01*
X1471234Y633691D01*
X1471563Y633857D01*
G03X1471669Y634002I-91J178D01*
G02X1476378Y637968I4709J-813D01*
G37*
G36*
G01X1424356Y633189D02*
Y633191D01*
G02X1429134Y637968I4778J-1D01*
G02X1432767Y636293I-1J-4779D01*
G03X1432919Y636223I152J130D01*
G01X1433223D01*
G03X1433375Y636293I0J200D01*
G02X1437008Y637968I3634J-3104D01*
G02X1441786Y633189I-1J-4779D01*
G02X1440112Y629556I-4779J0D01*
G03X1440042Y629404I130J-152D01*
G01Y629100D01*
G03X1440112Y628948I200J0D01*
G02Y621682I-3105J-3633D01*
G03X1440042Y621530I130J-152D01*
G01Y621226D01*
G03X1440112Y621074I200J0D01*
G02X1441786Y617441I-3105J-3633D01*
G01Y617439D01*
G02X1437008Y612662I-4778J1D01*
G02X1433375Y614337I1J4779D01*
G03X1433223Y614407I-152J-130D01*
G01X1432919D01*
G03X1432767Y614337I0J-200D01*
G02X1429134Y612662I-3634J3104D01*
G02X1424356Y617441I1J4779D01*
G02X1426030Y621074I4779J0D01*
G03X1426100Y621226I-130J152D01*
G01Y621530D01*
G03X1426030Y621682I-200J0D01*
G02Y628948I3105J3633D01*
G03X1426100Y629100I-130J152D01*
G01Y629404D01*
G03X1426030Y629556I-200J0D01*
G02X1424356Y633189I3105J3633D01*
G37*
G36*
G01X295276Y637968D02*
G02X298909Y636293I-1J-4779D01*
G03X299061Y636223I152J130D01*
G01X299365D01*
G03X299517Y636293I0J200D01*
G02X303150Y637968I3634J-3104D01*
G02X307928Y633189I-1J-4779D01*
G02X306254Y629556I-4779J0D01*
G03X306184Y629404I130J-152D01*
G01Y629100D01*
G03X306254Y628948I200J0D01*
G02Y621682I-3105J-3633D01*
G03X306184Y621530I130J-152D01*
G01Y621226D01*
G03X306254Y621074I200J0D01*
G02X307928Y617441I-3105J-3633D01*
G01Y617439D01*
G02X303150Y612662I-4778J1D01*
G02X299517Y614337I1J4779D01*
G03X299365Y614407I-152J-130D01*
G01X299061D01*
G03X298909Y614337I0J-200D01*
G02X295276Y612662I-3634J3104D01*
G02X290498Y617441I1J4779D01*
G02X292172Y621074I4779J0D01*
G03X292242Y621226I-130J152D01*
G01Y621530D01*
G03X292172Y621682I-200J0D01*
G02X290960Y623263I3103J3634D01*
G01X290942Y623301D01*
X290879Y623356D01*
X290555Y623454D01*
G03X290395Y623435I-58J-191D01*
G02X284409I-2993J5030D01*
G03X284249Y623454I-102J-172D01*
G01X283925Y623356D01*
X283862Y623301D01*
X283844Y623263D01*
G02X282632Y621682I-4315J2053D01*
G03X282562Y621530I130J-152D01*
G01Y621226D01*
G03X282632Y621074I200J0D01*
G02X284306Y617441I-3105J-3633D01*
G01Y617439D01*
G02X279528Y612662I-4778J1D01*
G02X275895Y614337I1J4779D01*
G03X275743Y614407I-152J-130D01*
G01X275439D01*
G03X275287Y614337I0J-200D01*
G02X271654Y612662I-3634J3104D01*
G02X266876Y617441I1J4779D01*
G02X268550Y621074I4779J0D01*
G03X268620Y621226I-130J152D01*
G01Y621530D01*
G03X268550Y621682I-200J0D01*
G02Y628948I3105J3633D01*
G03X268620Y629100I-130J152D01*
G01Y629404D01*
G03X268550Y629556I-200J0D01*
G02X266876Y633189I3105J3633D01*
G01Y633191D01*
G02X271654Y637968I4778J-1D01*
G02X275287Y636293I-1J-4779D01*
G03X275439Y636223I152J130D01*
G01X275743D01*
G03X275895Y636293I0J200D01*
G02X279528Y637968I3634J-3104D01*
G02X284237Y634002I0J-4779D01*
G03X284343Y633857I197J33D01*
G01X284629Y633712D01*
G03X284808Y633711I90J178D01*
G02X289996I2594J-5246D01*
G01X290039Y633690D01*
X290132Y633691D01*
X290461Y633857D01*
G03X290567Y634002I-91J178D01*
G02X295276Y637968I4709J-813D01*
G37*
G36*
G01X243254Y633189D02*
Y633191D01*
G02X248032Y637968I4778J-1D01*
G02X251665Y636293I-1J-4779D01*
G03X251817Y636223I152J130D01*
G01X252121D01*
G03X252273Y636293I0J200D01*
G02X255906Y637968I3634J-3104D01*
G02X260684Y633189I-1J-4779D01*
G02X259010Y629556I-4779J0D01*
G03X258940Y629404I130J-152D01*
G01Y629100D01*
G03X259010Y628948I200J0D01*
G02Y621682I-3105J-3633D01*
G03X258940Y621530I130J-152D01*
G01Y621226D01*
G03X259010Y621074I200J0D01*
G02X260684Y617441I-3105J-3633D01*
G01Y617439D01*
G02X255906Y612662I-4778J1D01*
G02X252273Y614337I1J4779D01*
G03X252121Y614407I-152J-130D01*
G01X251817D01*
G03X251665Y614337I0J-200D01*
G02X248032Y612662I-3634J3104D01*
G02X243254Y617441I1J4779D01*
G02X244928Y621074I4779J0D01*
G03X244998Y621226I-130J152D01*
G01Y621530D01*
G03X244928Y621682I-200J0D01*
G02Y628948I3105J3633D01*
G03X244998Y629100I-130J152D01*
G01Y629404D01*
G03X244928Y629556I-200J0D01*
G02X243254Y633189I3105J3633D01*
G37*
G36*
G01X1197534Y318912D02*
Y318914D01*
G02X1201037Y315410I3503J-1D01*
G01X1200968D01*
X1200964D01*
X1200920Y315411D01*
X1200838Y315374D01*
X1200608Y315101D01*
G03X1200565Y314934I153J-129D01*
G02X1200630Y314264I-3438J-672D01*
G01Y314262D01*
G02X1197127Y317766I-3503J1D01*
G01X1197196D01*
X1197200D01*
X1197244Y317765D01*
X1197326Y317802D01*
X1197556Y318075D01*
G03X1197599Y318242I-153J129D01*
G02X1197534Y318912I3438J672D01*
G37*
G36*
G01X1176200Y312998D02*
X1176198D01*
G02X1174781Y313298I1J3502D01*
G03X1174619I-81J-183D01*
G02X1173202Y312998I-1418J3202D01*
G01X1173200D01*
G02Y320002I0J3502D01*
G01X1173202D01*
G02X1174619Y319702I-1J-3502D01*
G03X1174781I81J183D01*
G02X1176198Y320002I1418J-3202D01*
G01X1176200D01*
G02Y312998I0J-3502D01*
G37*
G36*
G01X587182Y310800D02*
G02X587482Y312219I3502J1D01*
G03Y312381I-183J81D01*
G02X587182Y313798I3202J1418D01*
G01Y313800D01*
G02X590684Y317302I3502J0D01*
G01X590687D01*
G02X592071Y317016I-2J-3502D01*
G03X592150Y317000I78J184D01*
G01X595500D01*
G02X596914Y316414I0J-1999D01*
G01X599414Y313914D01*
G02X600000Y312500I-1413J-1414D01*
G01Y288900D01*
G02X599414Y287486I-1999J0D01*
G01X598014Y286086D01*
G02X595186I-1414J1413D01*
G01X595086Y286186D01*
G02X594500Y287600I1413J1414D01*
G01Y292589D01*
G03X594441Y292731I-200J0D01*
G01X588586Y298586D01*
G02X588000Y300000I1413J1414D01*
G01Y308478D01*
G03X587956Y308604I-200J1D01*
G02X587182Y310800I2728J2196D01*
G37*
G36*
G01X1304198Y309900D02*
G02X1304498Y311319I3502J1D01*
G03Y311481I-183J81D01*
G02X1304198Y312898I3202J1418D01*
G01Y312900D01*
G02X1307700Y316402I3502J0D01*
G01X1307702D01*
G02X1309119Y316102I-1J-3502D01*
G03X1309281I81J183D01*
G02X1310698Y316402I1418J-3202D01*
G01X1310700D01*
G02X1314149Y313511I0J-3503D01*
G03X1314311Y313349I197J35D01*
G02X1317149Y310511I-611J-3449D01*
G03X1317311Y310349I197J35D01*
G02X1320149Y307511I-611J-3449D01*
G03X1320311Y307349I197J35D01*
G02X1323202Y303900I-612J-3449D01*
G01Y303898D01*
G02X1322902Y302481I-3502J1D01*
G03Y302319I183J-81D01*
G02X1323202Y300902I-3202J-1418D01*
G01Y300900D01*
G02X1319700Y297398I-3502J0D01*
G01X1319698D01*
G02X1318281Y297698I1J3502D01*
G03X1318119I-81J-183D01*
G02X1316700Y297398I-1418J3202D01*
G02X1315281Y297698I-1J3502D01*
G03X1315119I-81J-183D01*
G02X1313700Y297398I-1418J3202D01*
G02X1312281Y297698I-1J3502D01*
G03X1312119I-81J-183D01*
G02X1310700Y297398I-1418J3202D01*
G02X1309281Y297698I-1J3502D01*
G03X1309119I-81J-183D01*
G02X1307702Y297398I-1418J3202D01*
G01X1307700D01*
G02X1304198Y300900I0J3502D01*
G01Y300902D01*
G02X1304498Y302319I3502J-1D01*
G03Y302481I-183J81D01*
G02X1304198Y303900I3202J1418D01*
G02X1304498Y305319I3502J1D01*
G03Y305481I-183J81D01*
G02X1304198Y306900I3202J1418D01*
G02X1304498Y308319I3502J1D01*
G03Y308481I-183J81D01*
G02X1304198Y309900I3202J1418D01*
G37*
G36*
G01X1106661Y304198D02*
X1106659D01*
G02X1105242Y304498I1J3502D01*
G03X1105080I-81J-183D01*
G02X1103663Y304198I-1418J3202D01*
G01X1103661D01*
G02Y311202I0J3502D01*
G01X1103663D01*
G02X1105080Y310902I-1J-3502D01*
G03X1105242I81J183D01*
G02X1106659Y311202I1418J-3202D01*
G01X1106661D01*
G02Y304198I0J-3502D01*
G37*
G36*
G01X565091Y299090D02*
G02Y306094I0J3502D01*
G01X565092D01*
G02X567440Y305190I0J-3502D01*
G01X567469Y305164D01*
X567540Y305137D01*
X567853Y305143D01*
G03X567989Y305201I-5J200D01*
G02X570442Y306204I2453J-2499D01*
G01X570443D01*
G02Y299200I0J-3502D01*
G01X570442D01*
G02X568094Y300104I0J3502D01*
G01X568065Y300130D01*
X567994Y300157D01*
X567681Y300151D01*
G03X567545Y300093I5J-200D01*
G02X565092Y299090I-2453J2499D01*
G01X565091D01*
G37*
G36*
G01X1840590Y300433D02*
Y300435D01*
G02X1846142Y305986I5552J-1D01*
G02X1851100Y302933I0J-5552D01*
G01X1851125Y302882D01*
X1851221Y302823D01*
X1851693D01*
X1851789Y302882D01*
X1851814Y302933D01*
G02X1856772Y305986I4958J-2499D01*
G02X1862324Y300433I-1J-5553D01*
G02X1859785Y295769I-5553J0D01*
G01X1859742Y295741D01*
X1859693Y295652D01*
Y295214D01*
X1859742Y295125D01*
X1859785Y295097D01*
G02Y285769I-3014J-4664D01*
G01X1859742Y285741D01*
X1859693Y285652D01*
Y285214D01*
X1859742Y285125D01*
X1859785Y285097D01*
G02Y275769I-3014J-4664D01*
G01X1859742Y275741D01*
X1859693Y275652D01*
Y275214D01*
X1859742Y275125D01*
X1859785Y275097D01*
G02X1862324Y270433I-3014J-4664D01*
G01Y270431D01*
G02X1856772Y264880I-5552J1D01*
G02X1851814Y267933I0J5552D01*
G01X1851789Y267984D01*
X1851693Y268043D01*
X1851221D01*
X1851125Y267984D01*
X1851100Y267933D01*
G02X1846142Y264880I-4958J2499D01*
G02X1840590Y270433I1J5553D01*
G02X1843129Y275097I5553J0D01*
G01X1843172Y275125D01*
X1843221Y275214D01*
Y275652D01*
X1843172Y275741D01*
X1843129Y275769D01*
G02Y285097I3014J4664D01*
G01X1843172Y285125D01*
X1843221Y285214D01*
Y285652D01*
X1843172Y285741D01*
X1843129Y285769D01*
G02Y295097I3014J4664D01*
G01X1843172Y295125D01*
X1843221Y295214D01*
Y295652D01*
X1843172Y295741D01*
X1843129Y295769D01*
G02X1840590Y300433I3014J4664D01*
G37*
G36*
G01X1199059Y290701D02*
X1198941D01*
G03X1198810Y290651I1J-200D01*
G02X1196500Y289782I-2309J2634D01*
G02Y296786I0J3502D01*
G02X1198810Y295917I1J-3503D01*
G03X1198941Y295867I132J150D01*
G01X1199059D01*
G03X1199190Y295917I-1J200D01*
G02X1201500Y296786I2309J-2634D01*
G02Y289782I0J-3502D01*
G02X1199190Y290651I-1J3503D01*
G03X1199059Y290701I-132J-150D01*
G37*
G36*
G01X568040Y289065D02*
Y289066D01*
G02X568410Y290633I3502J0D01*
G03X568398Y290832I-179J89D01*
G02X567822Y292757I2926J1924D01*
G02X574828I3503J0D01*
G02X574457Y291189I-3503J1D01*
G03X574469Y290990I179J-89D01*
G02X575044Y289068I-2928J-1923D01*
G01Y289065D01*
G02X568040I-3502J0D01*
G37*
G36*
G01X1055300Y287398D02*
X1055297D01*
G02X1053834Y287719I2J3502D01*
G03X1053666I-84J-182D01*
G02X1052203Y287398I-1465J3181D01*
G01X1052200D01*
G02Y294402I0J3502D01*
G01X1052203D01*
G02X1053666Y294081I-2J-3502D01*
G03X1053834I84J182D01*
G02X1055297Y294402I1465J-3181D01*
G01X1055300D01*
G02Y287398I0J-3502D01*
G37*
G36*
G01X448738Y293502D02*
G02X450157Y293202I1J-3502D01*
G03X450319I81J183D01*
G02X451738Y293502I1418J-3202D01*
G02X453157Y293202I1J-3502D01*
G03X453319I81J183D01*
G02X454736Y293502I1418J-3202D01*
G01X454738D01*
G02X458240Y290000I0J-3502D01*
G01Y289998D01*
G02X457940Y288581I-3502J1D01*
G03Y288419I183J-81D01*
G02X458240Y287000I-3202J-1418D01*
G02X457940Y285581I-3502J-1D01*
G03Y285419I183J-81D01*
G02X458240Y284000I-3202J-1418D01*
G02X457940Y282581I-3502J-1D01*
G03Y282419I183J-81D01*
G02X458240Y281000I-3202J-1418D01*
G02X457940Y279581I-3502J-1D01*
G03Y279419I183J-81D01*
G02X458240Y278002I-3202J-1418D01*
G01Y278000D01*
G02X454738Y274498I-3502J0D01*
G01X454736D01*
G02X453319Y274798I1J3502D01*
G03X453157I-81J-183D01*
G02X451738Y274498I-1418J3202D01*
G02X450319Y274798I-1J3502D01*
G03X450157I-81J-183D01*
G02X448738Y274498I-1418J3202D01*
G02X447319Y274798I-1J3502D01*
G03X447157I-81J-183D01*
G02X445738Y274498I-1418J3202D01*
G02X444319Y274798I-1J3502D01*
G03X444157I-81J-183D01*
G02X442740Y274498I-1418J3202D01*
G01X442738D01*
G02X439236Y278000I0J3502D01*
G01Y278002D01*
G02X439536Y279419I3502J-1D01*
G03Y279581I-183J81D01*
G02X439236Y281000I3202J1418D01*
G02X439536Y282419I3502J1D01*
G03Y282581I-183J81D01*
G02X439236Y284000I3202J1418D01*
G02X439536Y285419I3502J1D01*
G03Y285581I-183J81D01*
G02X439236Y287000I3202J1418D01*
G02X439536Y288419I3502J1D01*
G03Y288581I-183J81D01*
G02X439236Y289998I3202J1418D01*
G01Y290000D01*
G02X442738Y293502I3502J0D01*
G01X442740D01*
G02X444157Y293202I-1J-3502D01*
G03X444319I81J183D01*
G02X445738Y293502I1418J-3202D01*
G02X447157Y293202I1J-3502D01*
G03X447319I81J183D01*
G02X448738Y293502I1418J-3202D01*
G37*
G36*
G01X586796Y282890D02*
G02X593800I3502J0D01*
G02X592588Y280240I-3503J0D01*
G03X592519Y280089I131J-151D01*
G01Y279785D01*
G03X592588Y279634I200J0D01*
G02X593800Y276984I-2291J-2650D01*
G02X586796I-3502J0D01*
G02X588008Y279634I3503J0D01*
G03X588077Y279785I-131J151D01*
G01Y280089D01*
G03X588008Y280240I-200J0D01*
G02X586796Y282890I2291J2650D01*
G37*
G36*
G01X1032500Y278298D02*
X1032498D01*
G02X1031081Y278598I1J3502D01*
G03X1030919I-81J-183D01*
G02X1029502Y278298I-1418J3202D01*
G01X1029500D01*
G02Y285302I0J3502D01*
G01X1029502D01*
G02X1030919Y285002I-1J-3502D01*
G03X1031081I81J183D01*
G02X1032498Y285302I1418J-3202D01*
G01X1032500D01*
G02Y278298I0J-3502D01*
G37*
G36*
G01X1059300Y276098D02*
X1059298D01*
G02X1057550Y276566I1J3502D01*
G03X1057350I-100J-173D01*
G02X1055602Y276098I-1749J3034D01*
G01X1055600D01*
G02Y283102I0J3502D01*
G01X1055602D01*
G02X1057350Y282634I-1J-3502D01*
G03X1057550I100J173D01*
G02X1059298Y283102I1749J-3034D01*
G01X1059300D01*
G02Y276098I0J-3502D01*
G37*
G36*
G01X715982Y278980D02*
G02X722986I3502J0D01*
G02X720657Y275680I-3502J0D01*
G01X720615Y275665D01*
X720553Y275604D01*
X720430Y275276D01*
G03X720442Y275108I187J-71D01*
G02X720886Y273403I-3058J-1707D01*
G01Y273400D01*
G02X713882I-3502J0D01*
G02X716211Y276700I3502J0D01*
G01X716253Y276715D01*
X716315Y276776D01*
X716438Y277104D01*
G03X716426Y277272I-187J71D01*
G02X715982Y278977I3058J1707D01*
G01Y278980D01*
G37*
G36*
G01X1041398Y278600D02*
G02X1048402I3502J0D01*
G02X1046073Y275300I-3502J0D01*
G01X1046031Y275285D01*
X1045969Y275224D01*
X1045846Y274896D01*
G03X1045858Y274728I187J-71D01*
G02X1046302Y273023I-3058J-1707D01*
G01Y273020D01*
G02X1039298I-3502J0D01*
G02X1041627Y276320I3502J0D01*
G01X1041669Y276335D01*
X1041731Y276396D01*
X1041854Y276724D01*
G03X1041842Y276892I-187J71D01*
G02X1041398Y278597I3058J1707D01*
G01Y278600D01*
G37*
G36*
G01X706684Y268898D02*
X706682D01*
G02X704934Y269366I1J3502D01*
G03X704734I-100J-173D01*
G02X702986Y268898I-1749J3034D01*
G01X702984D01*
G02Y275902I0J3502D01*
G01X702986D01*
G02X704734Y275434I-1J-3502D01*
G03X704934I100J173D01*
G02X706682Y275902I1749J-3034D01*
G01X706684D01*
G02Y268898I0J-3502D01*
G37*
G36*
G01X730600Y266498D02*
X730598D01*
G02X729181Y266798I1J3502D01*
G03X729019I-81J-183D01*
G02X727602Y266498I-1418J3202D01*
G01X727600D01*
G02Y273502I0J3502D01*
G01X727602D01*
G02X729019Y273202I-1J-3502D01*
G03X729181I81J183D01*
G02X730598Y273502I1418J-3202D01*
G01X730600D01*
G02Y266498I0J-3502D01*
G37*
G36*
G01X1313700Y272002D02*
G02X1315119Y271702I1J-3502D01*
G03X1315281I81J183D01*
G02X1316700Y272002I1418J-3202D01*
G02X1318119Y271702I1J-3502D01*
G03X1318281I81J183D01*
G02X1319698Y272002I1418J-3202D01*
G01X1319700D01*
G02X1323202Y268500I0J-3502D01*
G01Y268498D01*
G02X1322902Y267081I-3502J1D01*
G03Y266919I183J-81D01*
G02X1323202Y265500I-3202J-1418D01*
G02X1322902Y264081I-3502J-1D01*
G03Y263919I183J-81D01*
G02X1323202Y262500I-3202J-1418D01*
G02X1322902Y261081I-3502J-1D01*
G03Y260919I183J-81D01*
G02X1323202Y259500I-3202J-1418D01*
G02X1322902Y258081I-3502J-1D01*
G03Y257919I183J-81D01*
G02X1323202Y256502I-3202J-1418D01*
G01Y256500D01*
G02X1319700Y252998I-3502J0D01*
G01X1319698D01*
G02X1318281Y253298I1J3502D01*
G03X1318119I-81J-183D01*
G02X1316700Y252998I-1418J3202D01*
G02X1315281Y253298I-1J3502D01*
G03X1315119I-81J-183D01*
G02X1313700Y252998I-1418J3202D01*
G02X1312281Y253298I-1J3502D01*
G03X1312119I-81J-183D01*
G02X1310700Y252998I-1418J3202D01*
G02X1309281Y253298I-1J3502D01*
G03X1309119I-81J-183D01*
G02X1307702Y252998I-1418J3202D01*
G01X1307700D01*
G02X1304198Y256500I0J3502D01*
G01Y256502D01*
G02X1304498Y257919I3502J-1D01*
G03Y258081I-183J81D01*
G02X1304198Y259500I3202J1418D01*
G02X1304498Y260919I3502J1D01*
G03Y261081I-183J81D01*
G02X1304198Y262500I3202J1418D01*
G02X1304498Y263919I3502J1D01*
G03Y264081I-183J81D01*
G02X1304198Y265500I3202J1418D01*
G02X1304498Y266919I3502J1D01*
G03Y267081I-183J81D01*
G02X1304198Y268498I3202J1418D01*
G01Y268500D01*
G02X1307700Y272002I3502J0D01*
G01X1307702D01*
G02X1309119Y271702I-1J-3502D01*
G03X1309281I81J183D01*
G02X1310700Y272002I1418J-3202D01*
G02X1312119Y271702I1J-3502D01*
G03X1312281I81J183D01*
G02X1313700Y272002I1418J-3202D01*
G37*
G36*
G01X1059300Y264998D02*
X1059298D01*
G02X1057550Y265466I1J3502D01*
G03X1057350I-100J-173D01*
G02X1055602Y264998I-1749J3034D01*
G01X1055600D01*
G02Y272002I0J3502D01*
G01X1055602D01*
G02X1057350Y271534I-1J-3502D01*
G03X1057550I100J173D01*
G02X1059298Y272002I1749J-3034D01*
G01X1059300D01*
G02Y264998I0J-3502D01*
G37*
G36*
G01X710084Y257598D02*
X710081D01*
G02X708618Y257919I2J3502D01*
G03X708450I-84J-182D01*
G02X706987Y257598I-1465J3181D01*
G01X706984D01*
G02Y264602I0J3502D01*
G01X706987D01*
G02X708450Y264281I-2J-3502D01*
G03X708618I84J182D01*
G02X710081Y264602I1465J-3181D01*
G01X710084D01*
G02Y257598I0J-3502D01*
G37*
G36*
G01X448738Y249102D02*
G02X450157Y248802I1J-3502D01*
G03X450319I81J183D01*
G02X451738Y249102I1418J-3202D01*
G02X453157Y248802I1J-3502D01*
G03X453319I81J183D01*
G02X454736Y249102I1418J-3202D01*
G01X454738D01*
G02X458240Y245600I0J-3502D01*
G01Y245598D01*
G02X457940Y244181I-3502J1D01*
G03Y244019I183J-81D01*
G02X458240Y242600I-3202J-1418D01*
G02X457940Y241181I-3502J-1D01*
G03Y241019I183J-81D01*
G02X458240Y239600I-3202J-1418D01*
G02X457940Y238181I-3502J-1D01*
G03Y238019I183J-81D01*
G02X458240Y236600I-3202J-1418D01*
G02X457940Y235181I-3502J-1D01*
G03Y235019I183J-81D01*
G02X458240Y233602I-3202J-1418D01*
G01Y233600D01*
G02X454738Y230098I-3502J0D01*
G01X454736D01*
G02X453319Y230398I1J3502D01*
G03X453157I-81J-183D01*
G02X451738Y230098I-1418J3202D01*
G02X450319Y230398I-1J3502D01*
G03X450157I-81J-183D01*
G02X448738Y230098I-1418J3202D01*
G02X447319Y230398I-1J3502D01*
G03X447157I-81J-183D01*
G02X445738Y230098I-1418J3202D01*
G02X444319Y230398I-1J3502D01*
G03X444157I-81J-183D01*
G02X442740Y230098I-1418J3202D01*
G01X442738D01*
G02X439236Y233600I0J3502D01*
G01Y233602D01*
G02X439536Y235019I3502J-1D01*
G03Y235181I-183J81D01*
G02X439236Y236600I3202J1418D01*
G02X439536Y238019I3502J1D01*
G03Y238181I-183J81D01*
G02X439236Y239600I3202J1418D01*
G02X439536Y241019I3502J1D01*
G03Y241181I-183J81D01*
G02X439236Y242600I3202J1418D01*
G02X439536Y244019I3502J1D01*
G03Y244181I-183J81D01*
G02X439236Y245598I3202J1418D01*
G01Y245600D01*
G02X442738Y249102I3502J0D01*
G01X442740D01*
G02X444157Y248802I-1J-3502D01*
G03X444319I81J183D01*
G02X445738Y249102I1418J-3202D01*
G02X447157Y248802I1J-3502D01*
G03X447319I81J183D01*
G02X448738Y249102I1418J-3202D01*
G37*
G36*
G01X658600Y234198D02*
X658598D01*
G02X657181Y234498I1J3502D01*
G03X657019I-81J-183D01*
G02X655602Y234198I-1418J3202D01*
G01X655600D01*
G02Y241202I0J3502D01*
G01X655602D01*
G02X657019Y240902I-1J-3502D01*
G03X657181I81J183D01*
G02X658598Y241202I1418J-3202D01*
G01X658600D01*
G02Y234198I0J-3502D01*
G37*
G36*
G01X1070600Y231502D02*
G02X1072019Y231202I1J-3502D01*
G03X1072181I81J183D01*
G02X1073598Y231502I1418J-3202D01*
G01X1073600D01*
G02Y224498I0J-3502D01*
G01X1073598D01*
G02X1072181Y224798I1J3502D01*
G03X1072019I-81J-183D01*
G02X1070600Y224498I-1418J3202D01*
G02X1067907Y225760I-1J3502D01*
G01X1067879Y225794D01*
X1067799Y225832D01*
X1067401D01*
X1067321Y225794D01*
X1067293Y225760D01*
G02X1064600Y224498I-2692J2240D01*
G02X1063181Y224798I-1J3502D01*
G03X1063019I-81J-183D01*
G02X1061602Y224498I-1418J3202D01*
G01X1061600D01*
G02Y231502I0J3502D01*
G01X1061602D01*
G02X1063019Y231202I-1J-3502D01*
G03X1063181I81J183D01*
G02X1064600Y231502I1418J-3202D01*
G02X1067293Y230240I1J-3502D01*
G01X1067321Y230206D01*
X1067401Y230168D01*
X1067799D01*
X1067879Y230206D01*
X1067907Y230240D01*
G02X1070600Y231502I2692J-2240D01*
G37*
G36*
G01X1313700Y227602D02*
G02X1315119Y227302I1J-3502D01*
G03X1315281I81J183D01*
G02X1316700Y227602I1418J-3202D01*
G02X1318119Y227302I1J-3502D01*
G03X1318281I81J183D01*
G02X1319698Y227602I1418J-3202D01*
G01X1319700D01*
G02X1323202Y224100I0J-3502D01*
G01Y224098D01*
G02X1322902Y222681I-3502J1D01*
G03Y222519I183J-81D01*
G02X1323202Y221100I-3202J-1418D01*
G02X1322902Y219681I-3502J-1D01*
G03Y219519I183J-81D01*
G02X1323202Y218100I-3202J-1418D01*
G02X1322902Y216681I-3502J-1D01*
G03Y216519I183J-81D01*
G02X1323202Y215100I-3202J-1418D01*
G02X1322902Y213681I-3502J-1D01*
G03Y213519I183J-81D01*
G02X1323202Y212102I-3202J-1418D01*
G01Y212100D01*
G02X1319700Y208598I-3502J0D01*
G01X1319698D01*
G02X1318281Y208898I1J3502D01*
G03X1318119I-81J-183D01*
G02X1316700Y208598I-1418J3202D01*
G02X1315281Y208898I-1J3502D01*
G03X1315119I-81J-183D01*
G02X1313700Y208598I-1418J3202D01*
G02X1312281Y208898I-1J3502D01*
G03X1312119I-81J-183D01*
G02X1310700Y208598I-1418J3202D01*
G02X1309281Y208898I-1J3502D01*
G03X1309119I-81J-183D01*
G02X1307702Y208598I-1418J3202D01*
G01X1307700D01*
G02X1304198Y212100I0J3502D01*
G01Y212102D01*
G02X1304498Y213519I3502J-1D01*
G03Y213681I-183J81D01*
G02X1304198Y215100I3202J1418D01*
G02X1304498Y216519I3502J1D01*
G03Y216681I-183J81D01*
G02X1304198Y218100I3202J1418D01*
G02X1304498Y219519I3502J1D01*
G03Y219681I-183J81D01*
G02X1304198Y221100I3202J1418D01*
G02X1304498Y222519I3502J1D01*
G03Y222681I-183J81D01*
G02X1304198Y224098I3202J1418D01*
G01Y224100D01*
G02X1307700Y227602I3502J0D01*
G01X1307702D01*
G02X1309119Y227302I-1J-3502D01*
G03X1309281I81J183D01*
G02X1310700Y227602I1418J-3202D01*
G02X1312119Y227302I1J-3502D01*
G03X1312281I81J183D01*
G02X1313700Y227602I1418J-3202D01*
G37*
G36*
G01X448738Y204702D02*
G02X450157Y204402I1J-3502D01*
G03X450319I81J183D01*
G02X451738Y204702I1418J-3202D01*
G02X453157Y204402I1J-3502D01*
G03X453319I81J183D01*
G02X454736Y204702I1418J-3202D01*
G01X454738D01*
G02X458240Y201200I0J-3502D01*
G01Y201198D01*
G02X457940Y199781I-3502J1D01*
G03Y199619I183J-81D01*
G02X458240Y198200I-3202J-1418D01*
G02X457940Y196781I-3502J-1D01*
G03Y196619I183J-81D01*
G02X458240Y195200I-3202J-1418D01*
G02X457940Y193781I-3502J-1D01*
G03Y193619I183J-81D01*
G02X458240Y192200I-3202J-1418D01*
G02X457940Y190781I-3502J-1D01*
G03Y190619I183J-81D01*
G02X458240Y189202I-3202J-1418D01*
G01Y189200D01*
G02X454738Y185698I-3502J0D01*
G01X454736D01*
G02X453319Y185998I1J3502D01*
G03X453157I-81J-183D01*
G02X451738Y185698I-1418J3202D01*
G02X450319Y185998I-1J3502D01*
G03X450157I-81J-183D01*
G02X448738Y185698I-1418J3202D01*
G02X447319Y185998I-1J3502D01*
G03X447157I-81J-183D01*
G02X445738Y185698I-1418J3202D01*
G02X444319Y185998I-1J3502D01*
G03X444157I-81J-183D01*
G02X442740Y185698I-1418J3202D01*
G01X442738D01*
G02X439236Y189200I0J3502D01*
G01Y189202D01*
G02X439536Y190619I3502J-1D01*
G03Y190781I-183J81D01*
G02X439236Y192200I3202J1418D01*
G02X439536Y193619I3502J1D01*
G03Y193781I-183J81D01*
G02X439236Y195200I3202J1418D01*
G02X439536Y196619I3502J1D01*
G03Y196781I-183J81D01*
G02X439236Y198200I3202J1418D01*
G02X439536Y199619I3502J1D01*
G03Y199781I-183J81D01*
G02X439236Y201198I3202J1418D01*
G01Y201200D01*
G02X442738Y204702I3502J0D01*
G01X442740D01*
G02X444157Y204402I-1J-3502D01*
G03X444319I81J183D01*
G02X445738Y204702I1418J-3202D01*
G02X447157Y204402I1J-3502D01*
G03X447319I81J183D01*
G02X448738Y204702I1418J-3202D01*
G37*
G36*
G01X1307700Y183202D02*
X1307702D01*
G02X1309119Y182902I-1J-3502D01*
G03X1309281I81J183D01*
G02X1310700Y183202I1418J-3202D01*
G02X1312119Y182902I1J-3502D01*
G03X1312281I81J183D01*
G02X1313698Y183202I1418J-3202D01*
G01X1313700D01*
G02X1317149Y180311I0J-3503D01*
G03X1317311Y180149I197J35D01*
G02X1318119Y179902I-612J-3449D01*
G03X1318281I81J183D01*
G02X1319698Y180202I1418J-3202D01*
G01X1319700D01*
G02X1323202Y176700I0J-3502D01*
G01Y176698D01*
G02X1322902Y175281I-3502J1D01*
G03Y175119I183J-81D01*
G02X1323202Y173700I-3202J-1418D01*
G02X1322902Y172281I-3502J-1D01*
G03Y172119I183J-81D01*
G02X1323202Y170700I-3202J-1418D01*
G02X1322902Y169281I-3502J-1D01*
G03Y169119I183J-81D01*
G02X1323202Y167702I-3202J-1418D01*
G01Y167700D01*
G02X1319700Y164198I-3502J0D01*
G01X1319698D01*
G02X1318281Y164498I1J3502D01*
G03X1318119I-81J-183D01*
G02X1316700Y164198I-1418J3202D01*
G02X1315281Y164498I-1J3502D01*
G03X1315119I-81J-183D01*
G02X1313700Y164198I-1418J3202D01*
G02X1312281Y164498I-1J3502D01*
G03X1312119I-81J-183D01*
G02X1310700Y164198I-1418J3202D01*
G02X1309281Y164498I-1J3502D01*
G03X1309119I-81J-183D01*
G02X1307702Y164198I-1418J3202D01*
G01X1307700D01*
G02X1304198Y167700I0J3502D01*
G01Y167702D01*
G02X1304498Y169119I3502J-1D01*
G03Y169281I-183J81D01*
G02X1304198Y170700I3202J1418D01*
G02X1304498Y172119I3502J1D01*
G03Y172281I-183J81D01*
G02X1304198Y173700I3202J1418D01*
G02X1304498Y175119I3502J1D01*
G03Y175281I-183J81D01*
G02X1304198Y176700I3202J1418D01*
G02X1304498Y178119I3502J1D01*
G03Y178281I-183J81D01*
G02X1304198Y179698I3202J1418D01*
G01Y179700D01*
G02X1307700Y183202I3502J0D01*
G37*
G36*
G01X448738Y160302D02*
G02X450157Y160002I1J-3502D01*
G03X450319I81J183D01*
G02X451738Y160302I1418J-3202D01*
G02X453157Y160002I1J-3502D01*
G03X453319I81J183D01*
G02X454736Y160302I1418J-3202D01*
G01X454738D01*
G02X458240Y156800I0J-3502D01*
G01Y156798D01*
G02X457940Y155381I-3502J1D01*
G03Y155219I183J-81D01*
G02X458240Y153800I-3202J-1418D01*
G02X457940Y152381I-3502J-1D01*
G03Y152219I183J-81D01*
G02X458240Y150800I-3202J-1418D01*
G02X457940Y149381I-3502J-1D01*
G03Y149219I183J-81D01*
G02X458240Y147800I-3202J-1418D01*
G02X457940Y146381I-3502J-1D01*
G03Y146219I183J-81D01*
G02X458240Y144802I-3202J-1418D01*
G01Y144800D01*
G02X454738Y141298I-3502J0D01*
G01X454736D01*
G02X453319Y141598I1J3502D01*
G03X453157I-81J-183D01*
G02X451738Y141298I-1418J3202D01*
G02X450319Y141598I-1J3502D01*
G03X450157I-81J-183D01*
G02X448738Y141298I-1418J3202D01*
G02X447319Y141598I-1J3502D01*
G03X447157I-81J-183D01*
G02X445738Y141298I-1418J3202D01*
G02X444319Y141598I-1J3502D01*
G03X444157I-81J-183D01*
G02X442740Y141298I-1418J3202D01*
G01X442738D01*
G02X439236Y144800I0J3502D01*
G01Y144802D01*
G02X439536Y146219I3502J-1D01*
G03Y146381I-183J81D01*
G02X439236Y147800I3202J1418D01*
G02X439536Y149219I3502J1D01*
G03Y149381I-183J81D01*
G02X439236Y150800I3202J1418D01*
G02X439536Y152219I3502J1D01*
G03Y152381I-183J81D01*
G02X439236Y153800I3202J1418D01*
G02X439536Y155219I3502J1D01*
G03Y155381I-183J81D01*
G02X439236Y156798I3202J1418D01*
G01Y156800D01*
G02X442738Y160302I3502J0D01*
G01X442740D01*
G02X444157Y160002I-1J-3502D01*
G03X444319I81J183D01*
G02X445738Y160302I1418J-3202D01*
G02X447157Y160002I1J-3502D01*
G03X447319I81J183D01*
G02X448738Y160302I1418J-3202D01*
G37*
G36*
G01X1313700Y138802D02*
G02X1315119Y138502I1J-3502D01*
G03X1315281I81J183D01*
G02X1316700Y138802I1418J-3202D01*
G02X1318119Y138502I1J-3502D01*
G03X1318281I81J183D01*
G02X1319698Y138802I1418J-3202D01*
G01X1319700D01*
G02X1323202Y135300I0J-3502D01*
G01Y135298D01*
G02X1322902Y133881I-3502J1D01*
G03Y133719I183J-81D01*
G02X1323202Y132300I-3202J-1418D01*
G02X1322902Y130881I-3502J-1D01*
G03Y130719I183J-81D01*
G02X1323202Y129300I-3202J-1418D01*
G02X1322902Y127881I-3502J-1D01*
G03Y127719I183J-81D01*
G02X1323202Y126300I-3202J-1418D01*
G02X1322902Y124881I-3502J-1D01*
G03Y124719I183J-81D01*
G02X1323202Y123302I-3202J-1418D01*
G01Y123300D01*
G02X1319700Y119798I-3502J0D01*
G01X1319698D01*
G02X1318281Y120098I1J3502D01*
G03X1318119I-81J-183D01*
G02X1316700Y119798I-1418J3202D01*
G02X1315281Y120098I-1J3502D01*
G03X1315119I-81J-183D01*
G02X1313700Y119798I-1418J3202D01*
G02X1312281Y120098I-1J3502D01*
G03X1312119I-81J-183D01*
G02X1310700Y119798I-1418J3202D01*
G02X1309281Y120098I-1J3502D01*
G03X1309119I-81J-183D01*
G02X1307702Y119798I-1418J3202D01*
G01X1307700D01*
G02X1304198Y123300I0J3502D01*
G01Y123302D01*
G02X1304498Y124719I3502J-1D01*
G03Y124881I-183J81D01*
G02X1304198Y126300I3202J1418D01*
G02X1304498Y127719I3502J1D01*
G03Y127881I-183J81D01*
G02X1304198Y129300I3202J1418D01*
G02X1304498Y130719I3502J1D01*
G03Y130881I-183J81D01*
G02X1304198Y132300I3202J1418D01*
G02X1304498Y133719I3502J1D01*
G03Y133881I-183J81D01*
G02X1304198Y135298I3202J1418D01*
G01Y135300D01*
G02X1307700Y138802I3502J0D01*
G01X1307702D01*
G02X1309119Y138502I-1J-3502D01*
G03X1309281I81J183D01*
G02X1310700Y138802I1418J-3202D01*
G02X1312119Y138502I1J-3502D01*
G03X1312281I81J183D01*
G02X1313700Y138802I1418J-3202D01*
G37*
G36*
G01X448738Y115902D02*
G02X450157Y115602I1J-3502D01*
G03X450319I81J183D01*
G02X451738Y115902I1418J-3202D01*
G02X453157Y115602I1J-3502D01*
G03X453319I81J183D01*
G02X454736Y115902I1418J-3202D01*
G01X454738D01*
G02X458240Y112400I0J-3502D01*
G01Y112398D01*
G02X457940Y110981I-3502J1D01*
G03Y110819I183J-81D01*
G02X458240Y109400I-3202J-1418D01*
G02X457940Y107981I-3502J-1D01*
G03Y107819I183J-81D01*
G02X458240Y106400I-3202J-1418D01*
G02X457940Y104981I-3502J-1D01*
G03Y104819I183J-81D01*
G02X458240Y103400I-3202J-1418D01*
G02X457940Y101981I-3502J-1D01*
G03Y101819I183J-81D01*
G02X458240Y100402I-3202J-1418D01*
G01Y100400D01*
G02X454738Y96898I-3502J0D01*
G01X454736D01*
G02X453319Y97198I1J3502D01*
G03X453157I-81J-183D01*
G02X451738Y96898I-1418J3202D01*
G02X450319Y97198I-1J3502D01*
G03X450157I-81J-183D01*
G02X448738Y96898I-1418J3202D01*
G02X447319Y97198I-1J3502D01*
G03X447157I-81J-183D01*
G02X445738Y96898I-1418J3202D01*
G02X444319Y97198I-1J3502D01*
G03X444157I-81J-183D01*
G02X442740Y96898I-1418J3202D01*
G01X442738D01*
G02X439236Y100400I0J3502D01*
G01Y100402D01*
G02X439536Y101819I3502J-1D01*
G03Y101981I-183J81D01*
G02X439236Y103400I3202J1418D01*
G02X439536Y104819I3502J1D01*
G03Y104981I-183J81D01*
G02X439236Y106400I3202J1418D01*
G02X439536Y107819I3502J1D01*
G03Y107981I-183J81D01*
G02X439236Y109400I3202J1418D01*
G02X439536Y110819I3502J1D01*
G03Y110981I-183J81D01*
G02X439236Y112398I3202J1418D01*
G01Y112400D01*
G02X442738Y115902I3502J0D01*
G01X442740D01*
G02X444157Y115602I-1J-3502D01*
G03X444319I81J183D01*
G02X445738Y115902I1418J-3202D01*
G02X447157Y115602I1J-3502D01*
G03X447319I81J183D01*
G02X448738Y115902I1418J-3202D01*
G37*
G36*
G01X1313700Y94402D02*
G02X1315119Y94102I1J-3502D01*
G03X1315281I81J183D01*
G02X1316700Y94402I1418J-3202D01*
G02X1318119Y94102I1J-3502D01*
G03X1318281I81J183D01*
G02X1319698Y94402I1418J-3202D01*
G01X1319700D01*
G02X1323202Y90900I0J-3502D01*
G01Y90898D01*
G02X1322902Y89481I-3502J1D01*
G03Y89319I183J-81D01*
G02X1323202Y87900I-3202J-1418D01*
G02X1322902Y86481I-3502J-1D01*
G03Y86319I183J-81D01*
G02X1323202Y84900I-3202J-1418D01*
G02X1322902Y83481I-3502J-1D01*
G03Y83319I183J-81D01*
G02X1323202Y81900I-3202J-1418D01*
G02X1322902Y80481I-3502J-1D01*
G03Y80319I183J-81D01*
G02X1323202Y78902I-3202J-1418D01*
G01Y78900D01*
G02X1319700Y75398I-3502J0D01*
G01X1319698D01*
G02X1318281Y75698I1J3502D01*
G03X1318119I-81J-183D01*
G02X1316700Y75398I-1418J3202D01*
G02X1315281Y75698I-1J3502D01*
G03X1315119I-81J-183D01*
G02X1313700Y75398I-1418J3202D01*
G02X1312281Y75698I-1J3502D01*
G03X1312119I-81J-183D01*
G02X1310700Y75398I-1418J3202D01*
G02X1309281Y75698I-1J3502D01*
G03X1309119I-81J-183D01*
G02X1307702Y75398I-1418J3202D01*
G01X1307700D01*
G02X1304198Y78900I0J3502D01*
G01Y78902D01*
G02X1304498Y80319I3502J-1D01*
G03Y80481I-183J81D01*
G02X1304198Y81900I3202J1418D01*
G02X1304498Y83319I3502J1D01*
G03Y83481I-183J81D01*
G02X1304198Y84900I3202J1418D01*
G02X1304498Y86319I3502J1D01*
G03Y86481I-183J81D01*
G02X1304198Y87900I3202J1418D01*
G02X1304498Y89319I3502J1D01*
G03Y89481I-183J81D01*
G02X1304198Y90898I3202J1418D01*
G01Y90900D01*
G02X1307700Y94402I3502J0D01*
G01X1307702D01*
G02X1309119Y94102I-1J-3502D01*
G03X1309281I81J183D01*
G02X1310700Y94402I1418J-3202D01*
G02X1312119Y94102I1J-3502D01*
G03X1312281I81J183D01*
G02X1313700Y94402I1418J-3202D01*
G37*
G36*
G01X448738Y71502D02*
G02X450157Y71202I1J-3502D01*
G03X450319I81J183D01*
G02X451738Y71502I1418J-3202D01*
G02X453157Y71202I1J-3502D01*
G03X453319I81J183D01*
G02X454736Y71502I1418J-3202D01*
G01X454738D01*
G02X458240Y68000I0J-3502D01*
G01Y67998D01*
G02X457940Y66581I-3502J1D01*
G03Y66419I183J-81D01*
G02X458240Y65000I-3202J-1418D01*
G02X457940Y63581I-3502J-1D01*
G03Y63419I183J-81D01*
G02X458240Y62000I-3202J-1418D01*
G02X457940Y60581I-3502J-1D01*
G03Y60419I183J-81D01*
G02X458240Y59000I-3202J-1418D01*
G02X457940Y57581I-3502J-1D01*
G03Y57419I183J-81D01*
G02X458240Y56002I-3202J-1418D01*
G01Y56000D01*
G02X454738Y52498I-3502J0D01*
G01X454736D01*
G02X453319Y52798I1J3502D01*
G03X453157I-81J-183D01*
G02X451738Y52498I-1418J3202D01*
G02X450319Y52798I-1J3502D01*
G03X450157I-81J-183D01*
G02X448738Y52498I-1418J3202D01*
G02X447319Y52798I-1J3502D01*
G03X447157I-81J-183D01*
G02X445738Y52498I-1418J3202D01*
G02X444319Y52798I-1J3502D01*
G03X444157I-81J-183D01*
G02X442740Y52498I-1418J3202D01*
G01X442738D01*
G02X439236Y56000I0J3502D01*
G01Y56002D01*
G02X439536Y57419I3502J-1D01*
G03Y57581I-183J81D01*
G02X439236Y59000I3202J1418D01*
G02X439536Y60419I3502J1D01*
G03Y60581I-183J81D01*
G02X439236Y62000I3202J1418D01*
G02X439536Y63419I3502J1D01*
G03Y63581I-183J81D01*
G02X439236Y65000I3202J1418D01*
G02X439536Y66419I3502J1D01*
G03Y66581I-183J81D01*
G02X439236Y67998I3202J1418D01*
G01Y68000D01*
G02X442738Y71502I3502J0D01*
G01X442740D01*
G02X444157Y71202I-1J-3502D01*
G03X444319I81J183D01*
G02X445738Y71502I1418J-3202D01*
G02X447157Y71202I1J-3502D01*
G03X447319I81J183D01*
G02X448738Y71502I1418J-3202D01*
G37*
G36*
G01X1406230Y24578D02*
G02X1407649Y24278I1J-3502D01*
G03X1407811I81J183D01*
G02X1409230Y24578I1418J-3202D01*
G02X1410649Y24278I1J-3502D01*
G03X1410811I81J183D01*
G02X1412228Y24578I1418J-3202D01*
G01X1412230D01*
G02X1415732Y21076I0J-3502D01*
G01Y21074D01*
G02X1415432Y19657I-3502J1D01*
G03Y19495I183J-81D01*
G02X1415732Y18076I-3202J-1418D01*
G02X1415432Y16657I-3502J-1D01*
G03Y16495I183J-81D01*
G02X1415732Y15078I-3202J-1418D01*
G01Y15076D01*
G02X1412230Y11574I-3502J0D01*
G01X1412228D01*
G02X1410811Y11874I1J3502D01*
G03X1410649I-81J-183D01*
G02X1409230Y11574I-1418J3202D01*
G02X1407811Y11874I-1J3502D01*
G03X1407649I-81J-183D01*
G02X1406230Y11574I-1418J3202D01*
G02X1404811Y11874I-1J3502D01*
G03X1404649I-81J-183D01*
G02X1403230Y11574I-1418J3202D01*
G02X1401811Y11874I-1J3502D01*
G03X1401649I-81J-183D01*
G02X1400230Y11574I-1418J3202D01*
G02X1398811Y11874I-1J3502D01*
G03X1398649I-81J-183D01*
G02X1397232Y11574I-1418J3202D01*
G01X1397230D01*
G02X1393728Y15076I0J3502D01*
G01Y15078D01*
G02X1394028Y16495I3502J-1D01*
G03Y16657I-183J81D01*
G02X1393728Y18076I3202J1418D01*
G02X1394028Y19495I3502J1D01*
G03Y19657I-183J81D01*
G02X1393728Y21074I3202J1418D01*
G01Y21076D01*
G02X1397230Y24578I3502J0D01*
G01X1397232D01*
G02X1398649Y24278I-1J-3502D01*
G03X1398811I81J183D01*
G02X1400230Y24578I1418J-3202D01*
G02X1401649Y24278I1J-3502D01*
G03X1401811I81J183D01*
G02X1403230Y24578I1418J-3202D01*
G02X1404649Y24278I1J-3502D01*
G03X1404811I81J183D01*
G02X1406230Y24578I1418J-3202D01*
G37*
G36*
G01X334500Y24502D02*
G02X335919Y24202I1J-3502D01*
G03X336081I81J183D01*
G02X337500Y24502I1418J-3202D01*
G02X338919Y24202I1J-3502D01*
G03X339081I81J183D01*
G02X340498Y24502I1418J-3202D01*
G01X340500D01*
G02X344002Y21000I0J-3502D01*
G01Y20998D01*
G02X343702Y19581I-3502J1D01*
G03Y19419I183J-81D01*
G02X344002Y18000I-3202J-1418D01*
G02X343702Y16581I-3502J-1D01*
G03Y16419I183J-81D01*
G02X344002Y15002I-3202J-1418D01*
G01Y15000D01*
G02X340500Y11498I-3502J0D01*
G01X340498D01*
G02X339081Y11798I1J3502D01*
G03X338919I-81J-183D01*
G02X337500Y11498I-1418J3202D01*
G02X336081Y11798I-1J3502D01*
G03X335919I-81J-183D01*
G02X334500Y11498I-1418J3202D01*
G02X333081Y11798I-1J3502D01*
G03X332919I-81J-183D01*
G02X331500Y11498I-1418J3202D01*
G02X330081Y11798I-1J3502D01*
G03X329919I-81J-183D01*
G02X328500Y11498I-1418J3202D01*
G02X327081Y11798I-1J3502D01*
G03X326919I-81J-183D01*
G02X325502Y11498I-1418J3202D01*
G01X325500D01*
G02X321998Y15000I0J3502D01*
G01Y15002D01*
G02X322298Y16419I3502J-1D01*
G03Y16581I-183J81D01*
G02X321998Y18000I3202J1418D01*
G02X322298Y19419I3502J1D01*
G03Y19581I-183J81D01*
G02X321998Y20998I3202J1418D01*
G01Y21000D01*
G02X325500Y24502I3502J0D01*
G01X325502D01*
G02X326919Y24202I-1J-3502D01*
G03X327081I81J183D01*
G02X328500Y24502I1418J-3202D01*
G02X329919Y24202I1J-3502D01*
G03X330081I81J183D01*
G02X331500Y24502I1418J-3202D01*
G02X332919Y24202I1J-3502D01*
G03X333081I81J183D01*
G02X334500Y24502I1418J-3202D01*
G37*
G36*
G01X1438098Y14529D02*
X1438089Y14470D01*
X1438139Y14362D01*
X1438551Y14105D01*
X1438670Y14107D01*
X1438719Y14141D01*
G02X1441417Y14976I2699J-3944D01*
G02Y5418I0J-4779D01*
G02X1436638Y10194I0J4779D01*
G01Y10200D01*
G02X1436639Y10227I4774J-163D01*
G01Y10228D01*
G03X1436520Y10411I-200J0D01*
G01X1436185Y10560D01*
G03X1435969Y10525I-81J-183D01*
G02X1438098Y14529I-4551J4988D01*
G37*
G36*
G01X247547D02*
X247538Y14470D01*
X247588Y14362D01*
X248000Y14105D01*
X248119Y14107D01*
X248168Y14141D01*
G02X250866Y14976I2699J-3944D01*
G01X250868D01*
G02X246088Y10197I-1J-4779D01*
G01Y10228D01*
G03X245969Y10411I-200J0D01*
G01X245634Y10560D01*
G03X245418Y10525I-81J-183D01*
G02X247547Y14529I-4551J4988D01*
G37*
G36*
G01X1038045Y350989D02*
X1097848D01*
G02X1099262Y350403I0J-1999D01*
G01X1102411Y347254D01*
G02X1102997Y345840I-1413J-1414D01*
G01Y338600D01*
G03X1103056Y338458I200J0D01*
G01X1104207Y337307D01*
G02X1104214Y337300I-704J-711D01*
G03X1104357Y337240I143J140D01*
G01X1108329D01*
G03X1108471Y337299I0J200D01*
G01X1110941Y339769D01*
G03X1111000Y339911I-141J142D01*
G01Y342103D01*
G03X1110941Y342245I-200J0D01*
G01X1110093Y343093D01*
G02X1110090Y343096I705J708D01*
G03X1110048Y343129I-144J-139D01*
G02X1109800Y343560I251J431D01*
G01Y347960D01*
G02X1110300Y348460I500J0D01*
G01X1115700D01*
G02X1116200Y347960I0J-500D01*
G01Y343560D01*
G02X1115952Y343129I-499J0D01*
G03X1115910Y343096I102J-172D01*
G02X1115907Y343093I-708J705D01*
G01X1115059Y342245D01*
G03X1115000Y342103I141J-142D01*
G01Y339000D01*
G02X1114414Y337586I-1999J0D01*
G01X1110654Y333826D01*
G02X1109240Y333240I-1414J1413D01*
G01X1104674D01*
G03X1104532Y333181I0J-200D01*
G01X1102994Y331643D01*
X1102966Y331591D01*
X1102961Y331561D01*
G02X1102411Y330526I-1964J380D01*
G01X1100743Y328858D01*
G02X1099329Y328272I-1414J1413D01*
G01X1053465D01*
G03X1053323Y328213I0J-200D01*
G01X1050172Y325062D01*
G03X1050113Y324920I141J-142D01*
G01Y309513D01*
G02X1049527Y308099I-1999J0D01*
G01X1047514Y306086D01*
G02X1046100Y305500I-1414J1413D01*
G01X1027100D01*
G02X1025686Y306086I0J1999D01*
G01X1024231Y307541D01*
G02X1023645Y308955I1413J1414D01*
G01Y336589D01*
G02X1024231Y338003I1999J0D01*
G01X1036631Y350403D01*
G02X1038045Y350989I1414J-1413D01*
G37*
G36*
G01X1225966Y319000D02*
X1275500D01*
G02X1276914Y318414I0J-1999D01*
G01X1279414Y315914D01*
G02X1280000Y314500I-1413J-1414D01*
G01Y51500D01*
G02X1279414Y50086I-1999J0D01*
G01X1276914Y47586D01*
G02X1275500Y47000I-1414J1413D01*
G01X1115567D01*
G02X1114153Y47586I0J1999D01*
G01X1099586Y62153D01*
G02X1099000Y63567I1413J1414D01*
G01Y106106D01*
G03X1098941Y106248I-200J0D01*
G01X1095248Y109941D01*
G03X1095106Y110000I-142J-141D01*
G01X910000D01*
G02X908586Y110586I0J1999D01*
G01X901586Y117586D01*
G02X901000Y119000I1413J1414D01*
G01Y185000D01*
G02X901586Y186414I1999J0D01*
G01X905086Y189914D01*
G02X906500Y190500I1414J-1413D01*
G01X956551D01*
G02X957965Y189914I0J-1999D01*
G01X981058Y166821D01*
G03X981200Y166762I142J141D01*
G01X985094D01*
G03X985279Y166886I0J200D01*
G01X985303Y166942D01*
X985279Y167060D01*
X970074Y182265D01*
G02X969488Y183679I1413J1414D01*
G01Y200875D01*
G02X970074Y202289I1999J0D01*
G01X972219Y204434D01*
G02X973633Y205020I1414J-1413D01*
G01X1013280D01*
G02X1013541Y205003I1J-2000D01*
G03X1013593I26J198D01*
G02X1013854Y205020I260J-1983D01*
G02X1015268Y204434I0J-1999D01*
G01X1017914Y201788D01*
G02X1018500Y200374I-1413J-1414D01*
G01Y188811D01*
G03X1018624Y188626I200J0D01*
G01X1018680Y188602D01*
X1018798Y188626D01*
X1033314Y203142D01*
G02X1034728Y203728I1414J-1413D01*
G01X1081317D01*
G03X1081459Y203787I0J200D01*
G01X1110586Y232914D01*
G02X1112000Y233500I1414J-1413D01*
G01X1154589D01*
G03X1154731Y233559I0J200D01*
G01X1165441Y244269D01*
G03X1165500Y244411I-141J142D01*
G01Y258000D01*
G02X1166086Y259414I1999J0D01*
G01X1171646Y264974D01*
G03X1171695Y265177I-141J141D01*
G01X1171568Y265570D01*
X1171483Y265643D01*
X1171427Y265652D01*
G02X1168484Y269110I560J3458D01*
G02X1169696Y271760I3503J0D01*
G03X1169765Y271911I-131J151D01*
G01Y272215D01*
G03X1169696Y272366I-200J0D01*
G02X1168484Y275016I2291J2650D01*
G02X1175488I3502J0D01*
G02X1174276Y272366I-3503J0D01*
G03X1174207Y272215I131J-151D01*
G01Y271911D01*
G03X1174276Y271760I200J0D01*
G02X1175488Y269110I-2291J-2650D01*
G01Y269105D01*
G02X1175345Y268117I-3502J3D01*
G01X1175333Y268077D01*
X1175343Y267997D01*
X1175509Y267710D01*
G03X1175636Y267615I173J99D01*
G02X1176478Y267184I-465J-1947D01*
G03X1176608Y267135I131J151D01*
G01X1184429D01*
G03X1184606Y267241I0J200D01*
G02X1190794I3094J-1642D01*
G03X1190971Y267135I177J94D01*
G01X1195493D01*
G03X1195688Y267290I0J200D01*
G02X1196013Y268153I3411J-792D01*
G03Y268343I-176J95D01*
G02X1195596Y270000I3087J1658D01*
G02X1196011Y271654I3504J0D01*
G03X1196010Y271842I-177J93D01*
G02X1195594Y273500I3091J1657D01*
G02X1196010Y275156I3506J0D01*
G03Y275344I-177J94D01*
G02X1195594Y277000I3090J1656D01*
G02X1202606I3506J0D01*
G02X1202190Y275344I-3506J0D01*
G03Y275156I177J-94D01*
G02X1202606Y273500I-3090J-1656D01*
G02X1202190Y271842I-3507J-1D01*
G03X1202189Y271654I176J-95D01*
G02X1202604Y270000I-3089J-1654D01*
G02X1202187Y268343I-3504J1D01*
G03Y268153I176J-95D01*
G02X1202512Y267290I-3086J-1655D01*
G03X1202707Y267135I195J45D01*
G01X1207229D01*
G03X1207406Y267241I0J200D01*
G02X1213594I3094J-1642D01*
G03X1213771Y267135I177J94D01*
G01X1218807D01*
G03X1218949Y267194I0J200D01*
G01X1221256Y269501D01*
G03X1221315Y269643I-141J142D01*
G01Y314349D01*
G02X1221901Y315763I1999J0D01*
G01X1224552Y318414D01*
G02X1225966Y319000I1414J-1413D01*
G37*
G36*
G01X486100D02*
X536375D01*
G02X537789Y318414I0J-1999D01*
G01X540259Y315944D01*
G02X540845Y314530I-1413J-1414D01*
G01Y269824D01*
G03X540904Y269682I200J0D01*
G01X543508Y267078D01*
G03X543650Y267019I142J141D01*
G01X548100D01*
G03X548280Y267132I0J200D01*
G02X554580I3150J-1533D01*
G03X554760Y267019I180J87D01*
G01X559271D01*
X559381Y267109D01*
X559395Y267180D01*
G02X559743Y268153I3435J-680D01*
G03Y268343I-176J95D01*
G02X559326Y270000I3087J1658D01*
G02X559741Y271654I3504J0D01*
G03X559740Y271842I-177J93D01*
G02X559324Y273500I3091J1657D01*
G02X559740Y275156I3506J0D01*
G03Y275344I-177J94D01*
G02X559324Y277000I3090J1656D01*
G02X566336I3506J0D01*
G02X565920Y275344I-3506J0D01*
G03Y275156I177J-94D01*
G02X566336Y273500I-3090J-1656D01*
G02X565920Y271842I-3507J-1D01*
G03X565919Y271654I176J-95D01*
G02X566334Y270000I-3089J-1654D01*
G02X565917Y268343I-3504J1D01*
G03Y268153I176J-95D01*
G02X566265Y267180I-3087J-1653D01*
G01X566279Y267109D01*
X566389Y267019D01*
X573137D01*
G03X573317Y267132I0J200D01*
G02X579617I3150J-1533D01*
G03X579797Y267019I180J87D01*
G01X590481D01*
G02X591895Y266433I0J-1999D01*
G01X592114Y266214D01*
G02X592700Y264800I-1413J-1414D01*
G01Y260711D01*
G03X592759Y260569I200J0D01*
G01X630869Y222459D01*
G03X631011Y222400I142J141D01*
G01X689500D01*
G02X690914Y221814I0J-1999D01*
G01X695517Y217211D01*
G02X696103Y215797I-1413J-1414D01*
G01Y210343D01*
G02X695517Y208929I-1999J0D01*
G01X686376Y199788D01*
G02X684962Y199202I-1414J1413D01*
G01X680373D01*
G03X680231Y199143I0J-200D01*
G01X679912Y198824D01*
G03X679853Y198682I141J-142D01*
G01Y172448D01*
G03X679912Y172306I200J0D01*
G01X685477Y166741D01*
G03X685619Y166682I142J141D01*
G01X730158D01*
G03X730348Y166819I0J200D01*
G01X730468Y167179D01*
G03X730399Y167402I-190J63D01*
G01X730398D01*
G02X730186Y167586I1201J1598D01*
G01X715686Y182086D01*
G02X715100Y183500I1413J1414D01*
G01Y200374D01*
G02X715686Y201788I1999J0D01*
G01X718332Y204434D01*
G02X719746Y205020I1414J-1413D01*
G01X759967D01*
G02X761381Y204434I0J-1999D01*
G01X763526Y202289D01*
G02X764112Y200875I-1413J-1414D01*
G01Y183679D01*
G02X763526Y182265I-1999J0D01*
G01X748847Y167586D01*
G02X748635Y167402I-1413J1414D01*
G01X748634D01*
G03X748565Y167179I121J-160D01*
G01X748685Y166819D01*
G03X748875Y166682I190J63D01*
G01X754000D01*
G03X754142Y166741I0J200D01*
G01X777315Y189914D01*
G02X778729Y190500I1414J-1413D01*
G01X827100D01*
G02X828514Y189914I0J-1999D01*
G01X832014Y186414D01*
G02X832600Y185000I-1413J-1414D01*
G01Y119000D01*
G02X832014Y117586I-1999J0D01*
G01X825014Y110586D01*
G02X823600Y110000I-1414J1413D01*
G01X638494D01*
G03X638352Y109941I0J-200D01*
G01X634659Y106248D01*
G03X634600Y106106I141J-142D01*
G01Y63567D01*
G02X634014Y62153I-1999J0D01*
G01X619447Y47586D01*
G02X618033Y47000I-1414J1413D01*
G01X486100D01*
G02X484686Y47586I0J1999D01*
G01X482186Y50086D01*
G02X481600Y51500I1413J1414D01*
G01Y314500D01*
G02X482186Y315914I1999J0D01*
G01X484686Y318414D01*
G02X486100Y319000I1414J-1413D01*
G37*
G36*
G01X704934Y286534D02*
G02X706684Y287002I1749J-3034D01*
G02Y279998I0J-3502D01*
G02X704934Y280466I-1J3502D01*
G03X704734I-100J-173D01*
G02X702984Y279998I-1749J3034D01*
G02Y287002I0J3502D01*
G02X704734Y286534I1J-3502D01*
G03X704934I100J173D01*
G37*
G54D57*
X243785Y200472D03*
X166785D03*
X243785Y280472D03*
X166785D03*
X243785Y360472D03*
X166785D03*
X243785Y440472D03*
X166785D03*
X243785Y520472D03*
X166785D03*
X1565500Y200472D03*
X1488500D03*
X1565500Y280472D03*
X1488500D03*
X1565500Y360472D03*
X1488500D03*
X1565500Y440472D03*
X1488500D03*
X1565500Y520472D03*
X1488500D03*
G54D56*
X1034360Y254000D03*
X725000Y292500D03*
X1320346Y289900D03*
Y245500D03*
X1332671Y190644D03*
X1334140Y146642D03*
X1320346Y112300D03*
Y67900D03*
X1173500Y298500D03*
X704240Y185000D03*
X632186Y338917D03*
X623500Y379000D03*
X441938Y309700D03*
Y265300D03*
Y220900D03*
Y176500D03*
Y132100D03*
Y87700D03*
X438100Y214500D03*
X430608Y211389D03*
X438100Y170000D03*
X428277Y167056D03*
G54D59*
X1451417Y10197D03*
X260866D03*
G54D60*
X940197Y200984D03*
X822087D03*
G54D58*
X1565500Y550000D03*
Y470000D03*
Y390000D03*
Y310000D03*
Y230000D03*
X1488500Y550000D03*
Y470000D03*
Y390000D03*
Y310000D03*
Y230000D03*
X243785Y550000D03*
Y470000D03*
Y390000D03*
Y310000D03*
Y230000D03*
X166785Y550000D03*
Y470000D03*
Y390000D03*
Y310000D03*
Y230000D03*
G54D55*
X263780Y659961D03*
X1444882D03*
G54D51*
X1851457Y220433D03*
X1856772Y360433D03*
G54D54*
X300866Y10197D03*
X1491417D03*
G54D52*
X1212478Y300181D03*
X1529100Y78500D03*
X231600Y81000D03*
X19685Y766166D03*
X1854331D03*
G54D50*
X940197Y313484D03*
X822087Y88484D03*
Y313484D03*
X940197Y88484D03*
G54D53*
X1673228Y236614D03*
Y411614D03*
X59055Y236614D03*
Y411594D03*
%LPC*%
G75*
G36*
G01X486511Y180500D02*
X555989D01*
G02X556131Y180441I0J-200D01*
G01X559541Y177031D01*
G02X559600Y176889I-141J-142D01*
G01Y164044D01*
G02X559495Y163867I-200J-1D01*
G03X557653Y160784I1659J-3083D01*
G03X557709Y160159I3502J-1D01*
G01X557718Y160110D01*
X557689Y160017D01*
X557131Y159459D01*
G02X556989Y159400I-142J141D01*
G01X547900D01*
G03X546486Y158814I0J-1999D01*
G01X542086Y154414D01*
G03X541500Y153000I1413J-1414D01*
G01Y133200D01*
G03X542086Y131786I1999J0D01*
G01X543266Y130606D01*
G03X544680Y130020I1414J1413D01*
G01X548775D01*
G02X548919Y129959I0J-200D01*
G03X553941I2511J2441D01*
G02X554085Y130020I144J-139D01*
G01X557169D01*
G02X557311Y129961I0J-200D01*
G01X559541Y127731D01*
G02X559600Y127589I-141J-142D01*
G01Y119287D01*
X559595Y119265D01*
G03X559505Y118477I3412J-789D01*
G03X559595Y117689I3502J1D01*
G01X559600Y117667D01*
Y114933D01*
X559595Y114911D01*
G03X559505Y114123I3412J-789D01*
G03X559595Y113335I3502J1D01*
G01X559600Y113313D01*
Y52911D01*
G02X559541Y52769I-200J0D01*
G01X557831Y51059D01*
G02X557689Y51000I-142J141D01*
G01X487011D01*
G02X486869Y51059I0J200D01*
G01X485659Y52269D01*
G02X485600Y52411I141J142D01*
G01Y179589D01*
G02X485659Y179731I200J0D01*
G01X486369Y180441D01*
G02X486511Y180500I142J-141D01*
G37*
G36*
G01X487011Y315000D02*
X535464D01*
G02X535606Y314941I0J-200D01*
G01X536786Y313761D01*
G02X536845Y313619I-141J-142D01*
G01Y268913D01*
G03X537431Y267499I1999J0D01*
G01X541325Y263605D01*
G03X542739Y263019I1414J1413D01*
G01X548986D01*
G02X549118Y262969I0J-200D01*
G03X551430Y262098I2311J2631D01*
G03X553742Y262969I1J3502D01*
G02X553874Y263019I132J-150D01*
G01X559400D01*
G02X559600Y262819I0J-200D01*
G01Y252487D01*
X559595Y252465D01*
G03X559505Y251677I3412J-789D01*
G03X559595Y250889I3502J1D01*
G01X559600Y250867D01*
Y248133D01*
X559595Y248111D01*
G03X559505Y247323I3412J-789D01*
G03X559595Y246535I3502J1D01*
G01X559600Y246513D01*
Y187911D01*
G02X559541Y187769I-200J0D01*
G01X556331Y184559D01*
G02X556189Y184500I-142J141D01*
G01X486511D01*
G02X486369Y184559I0J200D01*
G01X485659Y185269D01*
G02X485600Y185411I141J142D01*
G01Y313589D01*
G02X485659Y313731I200J0D01*
G01X486869Y314941D01*
G02X487011Y315000I142J-141D01*
G37*
G36*
G01X578911Y263019D02*
X584397D01*
G02X584539Y262960I0J-200D01*
G01X586041Y261458D01*
G02X586100Y261316I-141J-142D01*
G01Y237100D01*
G03X586686Y235686I1999J0D01*
G01X600586Y221786D01*
G03X602000Y221200I1414J1413D01*
G01X626389D01*
G02X626531Y221141I0J-200D01*
G01X630386Y217286D01*
G03X631800Y216700I1414J1413D01*
G01X690289D01*
G02X690431Y216641I0J-200D01*
G01X692044Y215028D01*
G02X692103Y214886I-141J-142D01*
G01Y211254D01*
G02X692044Y211112I-200J0D01*
G01X684193Y203261D01*
G02X684051Y203202I-142J141D01*
G01X679462D01*
G03X678048Y202616I0J-1999D01*
G01X676439Y201007D01*
G03X675853Y199593I1413J-1414D01*
G01Y171537D01*
G03X676439Y170123I1999J0D01*
G01X683294Y163268D01*
G03X684708Y162682I1414J1413D01*
G01X754911D01*
G03X756325Y163268I0J1999D01*
G01X779498Y186441D01*
G02X779640Y186500I142J-141D01*
G01X826189D01*
G02X826331Y186441I0J-200D01*
G01X828541Y184231D01*
G02X828600Y184089I-141J-142D01*
G01Y119911D01*
G02X828541Y119769I-200J0D01*
G01X822831Y114059D01*
G02X822689Y114000I-142J141D01*
G01X637583D01*
G03X636169Y113414I0J-1999D01*
G01X631186Y108431D01*
G03X630600Y107017I1413J-1414D01*
G01Y64478D01*
G02X630541Y64336I-200J0D01*
G01X617264Y51059D01*
G02X617122Y51000I-142J141D01*
G01X565511D01*
G02X565369Y51059I0J200D01*
G01X563659Y52769D01*
G02X563600Y52911I141J142D01*
G01Y110578D01*
X563688Y110687D01*
X563757Y110702D01*
G03X566509Y114123I-750J3421D01*
G03X565839Y116182I-3502J-1D01*
G02Y116418I162J118D01*
G03X566509Y118477I-2832J2060D01*
G03X563757Y121898I-3502J0D01*
G01X563688Y121913D01*
X563600Y122022D01*
Y127789D01*
G02X563659Y127931I200J0D01*
G01X565689Y129961D01*
G02X565831Y130020I142J-141D01*
G01X571575D01*
G02X571719Y129959I0J-200D01*
G03X576741I2511J2441D01*
G02X576885Y130020I144J-139D01*
G01X580120D01*
G03X581534Y130606I0J1999D01*
G01X583514Y132586D01*
G03X584100Y134000I-1413J1414D01*
G01Y151100D01*
G03X583514Y152514I-1999J0D01*
G01X577214Y158814D01*
G03X575800Y159400I-1414J-1413D01*
G01X568081D01*
G02X567923Y159478I0J200D01*
G01X567700Y159765D01*
X567682Y159855D01*
X567694Y159901D01*
G03X567807Y160784I-3389J882D01*
G03X564305Y164286I-3502J0D01*
G03X564031Y164275I3J-3502D01*
G01X563989Y164272D01*
X563911Y164299D01*
X563664Y164527D01*
G02X563600Y164674I136J147D01*
G01Y243778D01*
X563688Y243887D01*
X563757Y243902D01*
G03X566509Y247323I-750J3421D01*
G03X565839Y249382I-3502J-1D01*
G02Y249618I162J118D01*
G03X566509Y251677I-2832J2060D01*
G03X563757Y255098I-3502J0D01*
G01X563688Y255113D01*
X563600Y255222D01*
Y262819D01*
G02X563800Y263019I200J0D01*
G01X574023D01*
G02X574155Y262969I0J-200D01*
G03X576467Y262098I2311J2631D01*
G03X578779Y262969I1J3502D01*
G02X578911Y263019I132J-150D01*
G37*
G36*
G01X719159Y199605D02*
X720515Y200961D01*
G02X720657Y201020I142J-141D01*
G01X759056D01*
G02X759198Y200961I0J-200D01*
G01X760053Y200106D01*
G02X760112Y199964I-141J-142D01*
G01Y184590D01*
G02X760053Y184448I-200J0D01*
G01X746664Y171059D01*
G02X746522Y171000I-142J141D01*
G01X732511D01*
G02X732369Y171059I0J200D01*
G01X719159Y184269D01*
G02X719100Y184411I141J142D01*
G01Y199463D01*
G02X719159Y199605I200J0D01*
G37*
G36*
G01X1190270Y263135D02*
X1197800D01*
G02X1198000Y262935I0J-200D01*
G01Y255072D01*
G02X1197880Y254888I-200J-1D01*
G03X1195775Y251677I1397J-3211D01*
G03X1196445Y249618I3502J1D01*
G02Y249382I-162J-118D01*
G03X1195775Y247323I2832J-2060D01*
G03X1197880Y244112I3502J0D01*
G02X1198000Y243928I-80J-183D01*
G01Y165611D01*
G02X1197941Y165469I-200J0D01*
G01X1195917Y163445D01*
X1195887Y163430D01*
G03X1194279Y161822I1538J-3146D01*
G02X1194241Y161769I-179J89D01*
G01X1194031Y161559D01*
G02X1193889Y161500I-142J141D01*
G01X1183800D01*
G03X1182386Y160914I0J-1999D01*
G01X1176414Y154942D01*
G03X1175828Y153528I1413J-1414D01*
G01Y132192D01*
G03X1176414Y130778I1999J0D01*
G01X1176795Y130397D01*
G03X1178209Y129811I1414J1413D01*
G01X1185266D01*
G02X1185397Y129762I0J-200D01*
G03X1190003I2303J2637D01*
G02X1190134Y129811I131J-151D01*
G01X1196878D01*
G02X1197020Y129752I0J-200D01*
G01X1197941Y128831D01*
G02X1198000Y128689I-141J-142D01*
G01Y121872D01*
G02X1197880Y121688I-200J-1D01*
G03X1195775Y118477I1397J-3211D01*
G03X1196445Y116418I3502J1D01*
G02Y116182I-162J-118D01*
G03X1195775Y114123I2832J-2060D01*
G03X1197880Y110912I3502J0D01*
G02X1198000Y110728I-80J-183D01*
G01Y52911D01*
G02X1197941Y52769I-200J0D01*
G01X1196231Y51059D01*
G02X1196089Y51000I-142J141D01*
G01X1116478D01*
G02X1116336Y51059I0J200D01*
G01X1103059Y64336D01*
G02X1103000Y64478I141J142D01*
G01Y107017D01*
G03X1102414Y108431I-1999J0D01*
G01X1097431Y113414D01*
G03X1096017Y114000I-1414J-1413D01*
G01X910911D01*
G02X910769Y114059I0J200D01*
G01X905059Y119769D01*
G02X905000Y119911I141J142D01*
G01Y184089D01*
G02X905059Y184231I200J0D01*
G01X907269Y186441D01*
G02X907411Y186500I142J-141D01*
G01X955640D01*
G02X955782Y186441I0J-200D01*
G01X978875Y163348D01*
G03X980289Y162762I1414J1413D01*
G01X1077562D01*
G03X1078976Y163348I0J1999D01*
G01X1085714Y170086D01*
G03X1086300Y171500I-1413J1414D01*
G01Y196489D01*
G02X1086359Y196631I200J0D01*
G01X1089469Y199741D01*
G02X1089611Y199800I142J-141D01*
G01X1160800D01*
G03X1162214Y200386I0J1999D01*
G01X1168914Y207086D01*
G03X1169500Y208500I-1413J1414D01*
G01Y257089D01*
G02X1169559Y257231I200J0D01*
G01X1175404Y263076D01*
G02X1175546Y263135I142J-141D01*
G01X1185130D01*
G02X1185269Y263079I0J-200D01*
G03X1190131I2431J2522D01*
G02X1190270Y263135I139J-144D01*
G37*
G36*
G01X973547Y200106D02*
X974402Y200961D01*
G02X974544Y201020I142J-141D01*
G01X1012943D01*
G02X1013085Y200961I0J-200D01*
G01X1014441Y199605D01*
G02X1014500Y199463I-141J-142D01*
G01Y184411D01*
G02X1014441Y184269I-200J0D01*
G01X1001231Y171059D01*
G02X1001089Y171000I-142J141D01*
G01X987078D01*
G02X986936Y171059I0J200D01*
G01X973547Y184448D01*
G02X973488Y184590I141J142D01*
G01Y199964D01*
G02X973547Y200106I200J0D01*
G37*
G36*
G01X1204711Y180500D02*
X1275089D01*
G02X1275231Y180441I0J-200D01*
G01X1275941Y179731D01*
G02X1276000Y179589I-141J-142D01*
G01Y52411D01*
G02X1275941Y52269I-200J0D01*
G01X1274731Y51059D01*
G02X1274589Y51000I-142J141D01*
G01X1203911D01*
G02X1203769Y51059I0J200D01*
G01X1202059Y52769D01*
G02X1202000Y52911I141J142D01*
G01Y111851D01*
G02X1202042Y111974I200J0D01*
G03X1202779Y114123I-2765J2149D01*
G03X1202109Y116182I-3502J-1D01*
G02Y116418I162J118D01*
G03X1202779Y118477I-2832J2060D01*
G03X1202042Y120626I-3502J0D01*
G02X1202000Y120749I158J123D01*
G01Y128789D01*
G02X1202059Y128931I200J0D01*
G01X1202880Y129752D01*
G02X1203022Y129811I142J-141D01*
G01X1208066D01*
G02X1208197Y129762I0J-200D01*
G03X1212803I2303J2637D01*
G02X1212934Y129811I131J-151D01*
G01X1219382D01*
G03X1220796Y130397I0J1999D01*
G01X1224817Y134418D01*
G03X1225403Y135832I-1413J1414D01*
G01Y153697D01*
G03X1224817Y155111I-1999J0D01*
G01X1219014Y160914D01*
G03X1217600Y161500I-1414J-1413D01*
G01X1204111D01*
G02X1203969Y161559I0J200D01*
G01X1203736Y161792D01*
X1203721Y161822D01*
G03X1202113Y163430I-3146J-1538D01*
G01X1202083Y163445D01*
X1202059Y163469D01*
G02X1202000Y163611I141J142D01*
G01Y177789D01*
G02X1202059Y177931I200J0D01*
G01X1204569Y180441D01*
G02X1204711Y180500I142J-141D01*
G37*
G36*
G01X1226877Y315000D02*
X1274589D01*
G02X1274731Y314941I0J-200D01*
G01X1275941Y313731D01*
G02X1276000Y313589I-141J-142D01*
G01Y185411D01*
G02X1275941Y185269I-200J0D01*
G01X1275231Y184559D01*
G02X1275089Y184500I-142J141D01*
G01X1202200D01*
G02X1202000Y184700I0J200D01*
G01Y245051D01*
G02X1202042Y245174I200J0D01*
G03X1202779Y247323I-2765J2149D01*
G03X1202109Y249382I-3502J-1D01*
G02Y249618I162J118D01*
G03X1202779Y251677I-2832J2060D01*
G03X1202042Y253826I-3502J0D01*
G02X1202000Y253949I158J123D01*
G01Y262935D01*
G02X1202200Y263135I200J0D01*
G01X1207930D01*
G02X1208069Y263079I0J-200D01*
G03X1212931I2431J2522D01*
G02X1213070Y263135I139J-144D01*
G01X1219718D01*
G03X1221132Y263721I0J1999D01*
G01X1224729Y267318D01*
G03X1225315Y268732I-1413J1414D01*
G01Y313438D01*
G02X1225374Y313580I200J0D01*
G01X1226735Y314941D01*
G02X1226877Y315000I142J-141D01*
G37*
%LPD*%
G75*
G36*
G01X41338Y17716D02*
G03X53150I5906J0D01*
G01Y23763D01*
G02X55572Y32155I15747J1D01*
G03X38916I-8328J5246D01*
G02X41338Y23763I-13327J-8392D01*
G01Y17716D01*
G37*
G36*
G01Y330708D02*
G03X53150I5906J0D01*
G01Y336755D01*
G02X55572Y345147I15747J1D01*
G03X38916I-8328J5246D01*
G02X41338Y336755I-13327J-8392D01*
G01Y330708D01*
G37*
G36*
G01X273622Y53148D02*
G03X285434I5906J0D01*
G01Y59195D01*
G02X287856Y67587I15747J1D01*
G03X271200I-8328J5246D01*
G02X273622Y59195I-13327J-8392D01*
G01Y53148D01*
G37*
G36*
G01X309055Y561023D02*
G03X320867I5906J0D01*
G01Y567070D01*
G02X323289Y575462I15747J1D01*
G03X306633I-8328J5246D01*
G02X309055Y567070I-13327J-8392D01*
G01Y561023D01*
G37*
G36*
G01X387796Y344488D02*
G03X399608I5906J0D01*
G01Y350535D01*
G02X402030Y358927I15747J1D01*
G03X385374I-8328J5246D01*
G02X387796Y350535I-13327J-8392D01*
G01Y344488D01*
G37*
G36*
G01X742126Y64961D02*
G03X753938I5906J0D01*
G01Y71008D01*
G02X756360Y79400I15747J1D01*
G03X739704I-8328J5246D01*
G02X742126Y71008I-13327J-8392D01*
G01Y64961D01*
G37*
G36*
G01Y344488D02*
G03X753938I5906J0D01*
G01Y350535D01*
G02X756360Y358927I15747J1D01*
G03X739704I-8328J5246D01*
G02X742126Y350535I-13327J-8392D01*
G01Y344488D01*
G37*
G36*
G01X978346Y64961D02*
G03X990158I5906J0D01*
G01Y71008D01*
G02X992580Y79400I15747J1D01*
G03X975924I-8328J5246D01*
G02X978346Y71008I-13327J-8392D01*
G01Y64961D01*
G37*
G36*
G01Y344488D02*
G03X990158I5906J0D01*
G01Y350535D01*
G02X992580Y358927I15747J1D01*
G03X975924I-8328J5246D01*
G02X978346Y350535I-13327J-8392D01*
G01Y344488D01*
G37*
G36*
G01X1332678D02*
G03X1344490I5906J0D01*
G01Y350535D01*
G02X1346912Y358927I15747J1D01*
G03X1330256I-8328J5246D01*
G02X1332678Y350535I-13327J-8392D01*
G01Y344488D01*
G37*
G36*
G01X1411418Y561023D02*
G03X1423230I5906J0D01*
G01Y567070D01*
G02X1425652Y575462I15747J1D01*
G03X1408996I-8328J5246D01*
G02X1411418Y567070I-13327J-8392D01*
G01Y561023D01*
G37*
G36*
G01X1446850Y53149D02*
G03X1458662I5906J0D01*
G01Y59196D01*
G02X1461084Y67588I15747J1D01*
G03X1444428I-8328J5246D01*
G02X1446850Y59196I-13327J-8392D01*
G01Y53149D01*
G37*
G36*
G01X1679134Y17716D02*
G03X1690946I5906J0D01*
G01Y23763D01*
G02X1693368Y32155I15747J1D01*
G03X1676712I-8328J5246D01*
G02X1679134Y23763I-13327J-8392D01*
G01Y17716D01*
G37*
G36*
G01Y330708D02*
G03X1690946I5906J0D01*
G01Y336755D01*
G02X1693368Y345147I15747J1D01*
G03X1676712I-8328J5246D01*
G02X1679134Y336755I-13327J-8392D01*
G01Y330708D01*
G37*
G36*
G01X1793306Y96457D02*
G03X1805118I5906J0D01*
G01Y102504D01*
G02X1807540Y110896I15747J1D01*
G03X1790884I-8328J5246D01*
G02X1793306Y102504I-13327J-8392D01*
G01Y96457D01*
G37*
G36*
G01Y478346D02*
G03X1805118I5906J0D01*
G01Y484393D01*
G02X1807540Y492785I15747J1D01*
G03X1790884I-8328J5246D01*
G02X1793306Y484393I-13327J-8392D01*
G01Y478346D01*
G37*
G54D17*
X134600Y150000D03*
Y134000D03*
X156785Y101285D03*
X187600Y106500D03*
X176785Y102000D03*
X211425Y106075D03*
X210925Y115575D03*
X317000Y58000D03*
Y74475D03*
Y64500D03*
X325500Y15000D03*
Y18000D03*
Y21000D03*
X340500D03*
Y18000D03*
Y15000D03*
X337500Y21000D03*
Y18000D03*
Y15000D03*
X334500Y21000D03*
Y18000D03*
Y15000D03*
X331500Y21000D03*
Y18000D03*
Y15000D03*
X328500Y21000D03*
Y18000D03*
Y15000D03*
X321500Y74475D03*
Y66500D03*
X325100Y64000D03*
X332500Y63300D03*
X330500Y74476D03*
X326000D03*
X396216Y46875D03*
X428277Y167056D03*
X438100Y170000D03*
X430608Y211389D03*
X438100Y214500D03*
X454738Y56000D03*
X451738D03*
X448738D03*
X445738D03*
X442738D03*
X454738Y68000D03*
Y65000D03*
Y62000D03*
Y59000D03*
X451738D03*
Y62000D03*
Y65000D03*
Y68000D03*
X448738Y59000D03*
Y62000D03*
Y65000D03*
Y68000D03*
X445738Y59000D03*
Y62000D03*
Y65000D03*
Y68000D03*
X442738Y59000D03*
Y62000D03*
Y65000D03*
Y68000D03*
X441938Y87700D03*
X454738Y112400D03*
Y109400D03*
Y106400D03*
Y103400D03*
X451738D03*
Y106400D03*
Y109400D03*
Y112400D03*
X448738Y103400D03*
Y106400D03*
Y109400D03*
Y112400D03*
X445738Y103400D03*
Y106400D03*
Y109400D03*
Y112400D03*
X442738Y103400D03*
Y106400D03*
Y109400D03*
Y112400D03*
X454738Y100400D03*
X451738D03*
X448738D03*
X445738D03*
X442738D03*
X454738Y147800D03*
X451738D03*
X448738D03*
X445738D03*
X442738D03*
X454738Y144800D03*
X451738D03*
X448738D03*
X445738D03*
X442738D03*
X441938Y132100D03*
X454738Y156800D03*
Y153800D03*
Y150800D03*
X451738D03*
Y153800D03*
Y156800D03*
X448738Y150800D03*
Y153800D03*
Y156800D03*
X445738Y150800D03*
Y153800D03*
Y156800D03*
X442738Y150800D03*
Y153800D03*
Y156800D03*
X441938Y176500D03*
X454738Y201200D03*
Y198200D03*
Y195200D03*
Y192200D03*
X451738D03*
Y195200D03*
Y198200D03*
Y201200D03*
X448738Y192200D03*
Y195200D03*
Y198200D03*
Y201200D03*
X445738Y192200D03*
Y195200D03*
Y198200D03*
Y201200D03*
X442738Y192200D03*
Y195200D03*
Y198200D03*
Y201200D03*
X454738Y189200D03*
X451738D03*
X448738D03*
X445738D03*
X442738D03*
X454738Y239600D03*
Y236600D03*
X451738D03*
Y239600D03*
X448738Y236600D03*
Y239600D03*
X445738Y236600D03*
Y239600D03*
X442738Y236600D03*
Y239600D03*
X454738Y233600D03*
X451738D03*
X448738D03*
X445738D03*
X442738D03*
X441938Y220900D03*
X454738Y245600D03*
Y242600D03*
X451738D03*
Y245600D03*
X448738Y242600D03*
Y245600D03*
X445738Y242600D03*
Y245600D03*
X442738Y242600D03*
Y245600D03*
X441938Y265300D03*
X448738Y278000D03*
X451738D03*
X454738D03*
X448738Y290000D03*
Y287000D03*
Y284000D03*
Y281000D03*
X451738Y290000D03*
Y287000D03*
Y284000D03*
Y281000D03*
X454738D03*
Y284000D03*
Y287000D03*
Y290000D03*
X445738D03*
Y287000D03*
Y284000D03*
Y281000D03*
Y278000D03*
X442738Y290000D03*
Y287000D03*
Y284000D03*
Y281000D03*
Y278000D03*
X441938Y309700D03*
X517409Y322000D03*
X506309Y329000D03*
Y322000D03*
X517410Y329000D03*
X551430Y132400D03*
X561155Y160784D03*
X551430Y265600D03*
X563007Y118477D03*
Y114123D03*
X562830Y133300D03*
Y136800D03*
Y140300D03*
Y143800D03*
X574230Y132400D03*
X564305Y160784D03*
X563007Y251677D03*
X576467Y265600D03*
X563007Y247323D03*
X562830Y270000D03*
Y266500D03*
X590298Y282890D03*
X562830Y277000D03*
X571325Y292757D03*
X590298Y276984D03*
X562830Y273500D03*
X571542Y289065D03*
X565091Y302592D03*
X570443Y302702D03*
X595276Y239710D03*
X592476D03*
X620600Y239161D03*
X605800Y256500D03*
X609637Y254523D03*
X605700Y259500D03*
X616184Y267000D03*
X604684D03*
X612684Y297000D03*
X616684Y294500D03*
X602928Y293969D03*
X606084Y293100D03*
X600875Y295937D03*
X616184Y276000D03*
X604684D03*
Y285000D03*
X616184D03*
X590684Y313800D03*
Y310800D03*
X616684Y307975D03*
X622184Y308000D03*
X608259Y305000D03*
X618500Y333500D03*
X639010Y236377D03*
X640684Y264500D03*
Y269000D03*
X645900Y242200D03*
X644502Y246839D03*
X649200Y254500D03*
X650100Y251500D03*
X623684Y281000D03*
X637684Y280575D03*
X629018Y277500D03*
X625684Y273499D03*
X630308Y284500D03*
X632186Y338917D03*
X623500Y379000D03*
X676638Y230894D03*
X658600Y237700D03*
X655600D03*
X681684Y230820D03*
X657259Y263000D03*
X674800Y269600D03*
X660684Y262500D03*
X654100Y263000D03*
X651100Y266000D03*
X679184Y278980D03*
X673684Y280950D03*
X676684D03*
X670184Y288500D03*
X662184Y280500D03*
Y288500D03*
Y284500D03*
X679184Y273190D03*
X676184Y274000D03*
X657500Y330075D03*
X662075Y320000D03*
X675100Y304500D03*
X662125Y308500D03*
X662100Y304500D03*
X658925Y320000D03*
X702223Y197419D03*
X704240Y185000D03*
X689684Y230762D03*
X683592Y259908D03*
X688945Y259761D03*
X695259Y248020D03*
X706984Y261100D03*
X710084D03*
X691794Y261073D03*
X692109Y248020D03*
X686784Y268100D03*
X695584D03*
X698433Y247119D03*
X685884Y297000D03*
X702984Y283500D03*
X706684D03*
X702984Y272400D03*
X706684D03*
X686784Y278000D03*
X695584D03*
X686784Y287900D03*
X695684D03*
X710900Y324100D03*
X696613Y324032D03*
X693904D03*
X691759Y309000D03*
X712000Y215500D03*
X730600Y270000D03*
X727600D03*
X717384Y273400D03*
X719484Y278980D03*
X725000Y292500D03*
X722925Y299500D03*
X719433Y328087D03*
X734500Y307425D03*
X717401Y329996D03*
X770700Y206900D03*
X776000Y206600D03*
X862600Y29500D03*
X867100Y28000D03*
X872533Y29432D03*
X867100Y31500D03*
X887500Y355680D03*
X885100Y361500D03*
X885265Y381000D03*
X878175Y374100D03*
Y364709D03*
X894500Y396500D03*
X954200Y200200D03*
X954600Y207200D03*
X978600Y310955D03*
X1034537Y201437D03*
X1024600Y185000D03*
X1027675Y215000D03*
X1024525D03*
X1034360Y254000D03*
X1032500Y281800D03*
X1029500D03*
X1044900Y278600D03*
X1042800Y273020D03*
X1017300Y322500D03*
X1026270Y303729D03*
X1023492Y346593D03*
X1021414Y355979D03*
X1017300Y385600D03*
X1047163Y197437D03*
X1061600Y228000D03*
X1064600D03*
X1073600D03*
X1070600D03*
X1066600Y264100D03*
X1074430Y256461D03*
X1059300Y268500D03*
X1055600D03*
X1070525Y243000D03*
X1066700Y274000D03*
Y283900D03*
X1052200Y290900D03*
X1055300D03*
X1070490Y290927D03*
X1055600Y279600D03*
X1059300D03*
X1073339Y292239D03*
X1062600Y305000D03*
X1070175Y303980D03*
X1067025D03*
X1072600Y324000D03*
X1064600D03*
X1065800Y339500D03*
X1063300D03*
X1073800D03*
X1071300D03*
X1092100Y263500D03*
X1100100Y243500D03*
X1100500Y263500D03*
X1100100Y247500D03*
X1075500Y264100D03*
X1085600Y271050D03*
X1101500Y271500D03*
X1083100Y273020D03*
X1088079Y274980D03*
X1087100Y282500D03*
X1101600Y289500D03*
X1080600Y294000D03*
X1075500Y274000D03*
Y283900D03*
X1102600Y296000D03*
X1083100Y278810D03*
X1086100Y278000D03*
X1103661Y307700D03*
X1080600Y324000D03*
X1081800Y339500D03*
X1079300D03*
X1086800D03*
X1089300D03*
X1094500Y355600D03*
Y360500D03*
X1129800Y265400D03*
X1131976Y267500D03*
X1108100Y289000D03*
X1121600Y287500D03*
Y283000D03*
X1105025Y289000D03*
X1111100Y291500D03*
Y285000D03*
X1121100Y296000D03*
X1124600Y271425D03*
X1132113Y274500D03*
X1112000Y296000D03*
X1106661Y307700D03*
X1111100Y300500D03*
X1118000Y303500D03*
X1123100Y322500D03*
Y319500D03*
X1130100Y305174D03*
X1130510Y307720D03*
X1123400Y356300D03*
X1132000Y367000D03*
X1145600Y257500D03*
X1149600Y255000D03*
X1160990Y252134D03*
X1146100Y267000D03*
X1157600D03*
X1156200Y258900D03*
X1145600Y244025D03*
X1140100Y244000D03*
X1154025Y247000D03*
X1163266Y255311D03*
X1156584Y292488D03*
X1156509Y295396D03*
X1157600Y276000D03*
X1146100D03*
Y285000D03*
X1157600D03*
X1136000Y278953D03*
X1157800Y312050D03*
X1157138Y303000D03*
X1141600Y312839D03*
X1141500Y347500D03*
X1138500D03*
X1162425Y340500D03*
X1166000Y352500D03*
X1163000D03*
X1153500Y342500D03*
X1187700Y132400D03*
X1197425Y160284D03*
X1187700Y265600D03*
X1171986Y269110D03*
X1173500Y298500D03*
X1196500Y293284D03*
X1171986Y275016D03*
X1176200Y316500D03*
X1173200D03*
X1176000Y350000D03*
X1167800Y355000D03*
X1168200Y349700D03*
X1178900Y359620D03*
X1179500Y350000D03*
Y355000D03*
X1199277Y118477D03*
Y114123D03*
X1210500Y132400D03*
X1199100Y140300D03*
Y133300D03*
Y143800D03*
Y136800D03*
X1200575Y160284D03*
X1199277Y247323D03*
X1210500Y265600D03*
X1199277Y251677D03*
X1199100Y270000D03*
Y266500D03*
X1201500Y293284D03*
X1199100Y277000D03*
Y273500D03*
X1201037Y318912D03*
X1197127Y314264D03*
X1244874Y330000D03*
X1255975D03*
Y337000D03*
X1307700Y78900D03*
Y81900D03*
X1310700D03*
Y78900D03*
X1313700Y81900D03*
Y78900D03*
X1307700Y84900D03*
Y87900D03*
X1310700D03*
Y84900D03*
X1313700Y87900D03*
Y84900D03*
X1307700Y90900D03*
X1310700D03*
X1313700D03*
X1307700Y123300D03*
Y126300D03*
X1310700D03*
Y123300D03*
X1313700Y126300D03*
Y123300D03*
X1307700Y129300D03*
Y132300D03*
Y135300D03*
X1310700D03*
Y132300D03*
Y129300D03*
X1313700Y135300D03*
Y132300D03*
Y129300D03*
Y167700D03*
Y170700D03*
Y173700D03*
Y176700D03*
X1310700Y167700D03*
Y170700D03*
Y173700D03*
Y176700D03*
X1307700D03*
Y173700D03*
Y170700D03*
Y167700D03*
X1313700Y179700D03*
X1310700D03*
X1307700D03*
Y212100D03*
Y215100D03*
X1310700D03*
Y212100D03*
X1313700Y215100D03*
Y212100D03*
X1307700Y218100D03*
Y221100D03*
Y224100D03*
X1310700D03*
Y221100D03*
Y218100D03*
X1313700Y224100D03*
Y221100D03*
Y218100D03*
X1307700Y256500D03*
Y259500D03*
X1310700D03*
Y256500D03*
X1313700Y259500D03*
Y256500D03*
X1307700Y262500D03*
Y265500D03*
Y268500D03*
X1310700D03*
Y265500D03*
Y262500D03*
X1313700Y268500D03*
Y265500D03*
Y262500D03*
X1307700Y300900D03*
Y303900D03*
X1310700D03*
Y300900D03*
X1313700Y303900D03*
Y300900D03*
X1307700Y306900D03*
Y309900D03*
Y312900D03*
X1310700D03*
Y309900D03*
Y306900D03*
X1313700Y309900D03*
Y306900D03*
X1316700Y81900D03*
Y78900D03*
X1319700Y81900D03*
Y78900D03*
X1316700Y87900D03*
Y84900D03*
X1319700Y87900D03*
Y84900D03*
X1320346Y67900D03*
X1316700Y90900D03*
X1319700D03*
X1320346Y112300D03*
X1316700Y126300D03*
Y123300D03*
X1319700Y126300D03*
Y123300D03*
X1316700Y135300D03*
Y132300D03*
Y129300D03*
X1319700Y135300D03*
Y132300D03*
Y129300D03*
X1334140Y146642D03*
X1319700Y167700D03*
Y170700D03*
Y173700D03*
Y176700D03*
X1316700Y167700D03*
Y170700D03*
Y173700D03*
Y176700D03*
X1324100Y150500D03*
X1320346Y156700D03*
X1324100Y194900D03*
X1332671Y190644D03*
X1320346Y201100D03*
X1316700Y215100D03*
Y212100D03*
X1319700Y215100D03*
Y212100D03*
X1316700Y224100D03*
Y221100D03*
Y218100D03*
X1319700Y224100D03*
Y221100D03*
Y218100D03*
X1316700Y259500D03*
Y256500D03*
X1319700Y259500D03*
Y256500D03*
X1316700Y268500D03*
Y265500D03*
Y262500D03*
X1319700Y268500D03*
Y265500D03*
Y262500D03*
X1320346Y245500D03*
Y289900D03*
X1316700Y303900D03*
Y300900D03*
X1319700Y303900D03*
Y300900D03*
X1316700Y306900D03*
X1406230Y21076D03*
Y18076D03*
Y15076D03*
X1403230Y21076D03*
Y18076D03*
Y15076D03*
X1400230Y21076D03*
Y18076D03*
Y15076D03*
X1397230D03*
Y18076D03*
Y21076D03*
X1412230D03*
Y18076D03*
Y15076D03*
X1409230Y21076D03*
Y18076D03*
Y15076D03*
X1498180Y63500D03*
X1494728Y83500D03*
X1490000Y80500D03*
X1499228Y74500D03*
X1494728Y66500D03*
X1490228D03*
X1505100Y64500D03*
X1503728Y74477D03*
X1527100Y98925D03*
X1524600Y111500D03*
X1551000Y96500D03*
X1567500Y67000D03*
X1597100Y145000D03*
Y126000D03*
X1614100Y125000D03*
X1618100Y148925D03*
X1647800Y83200D03*
Y77200D03*
Y80200D03*
X1622295Y114940D03*
X1625370Y103940D03*
X1642037Y104134D03*
X1643537Y101434D03*
X1640037D03*
X1638537Y104134D03*
X1645537D03*
X1647037Y101434D03*
X1632336Y109117D03*
X1631323Y115140D03*
X1624500Y142500D03*
Y146000D03*
X1622295Y118940D03*
X1644917Y124581D03*
X1641932Y122969D03*
X1650117Y180000D03*
X1636600Y173500D03*
X1622100Y155931D03*
X1626000Y163500D03*
Y167500D03*
X1626925Y156000D03*
X1629000Y175000D03*
X1624000Y189000D03*
X1642000Y184500D03*
X1645000D03*
X1660250Y113860D03*
X1657050Y116760D03*
Y113860D03*
X1660250Y116760D03*
X1669800Y120400D03*
X1675800D03*
X1651037Y99734D03*
X1658500Y138000D03*
X1672800Y120400D03*
X1656657Y127365D03*
X1651325Y125076D03*
X1676350Y160251D03*
X1672050Y181550D03*
X1657500Y191500D03*
X1664000Y202500D03*
X1661500Y199000D03*
X1667600Y198500D03*
X1658000Y179500D03*
X1654000Y192500D03*
X1660000Y193500D03*
X1692000Y76570D03*
X1695500Y76500D03*
X1706100Y92000D03*
X1701350Y114250D03*
X1696600Y119000D03*
X1682500Y121825D03*
X1697976Y148000D03*
X1690100Y127375D03*
X1688100Y145560D03*
X1705100Y140500D03*
X1707100Y142500D03*
X1685000Y133000D03*
X1702600Y171500D03*
X1697976Y164500D03*
Y159000D03*
Y175500D03*
Y170000D03*
Y153500D03*
X1680000Y156500D03*
X1688100Y173060D03*
Y162060D03*
X1709600Y158000D03*
X1701000Y159000D03*
Y164500D03*
X1685975Y186500D03*
X1701100Y182000D03*
X1688100Y184220D03*
X1697975Y181000D03*
X1704600Y201500D03*
X1718675Y88000D03*
X1719075Y107016D03*
Y112000D03*
X1718675Y99000D03*
Y93500D03*
X1713524Y109500D03*
Y114500D03*
X1721685Y95940D03*
X1738000Y124500D03*
X1721000Y142525D03*
X1714100Y144925D03*
X1713525Y134500D03*
Y129500D03*
X1713524Y119500D03*
X1727100Y164280D03*
X1715525Y168500D03*
Y153000D03*
X1722063Y156962D03*
X1726099Y153000D03*
X1720524Y175000D03*
X1717600Y158000D03*
X1728475Y175000D03*
X1731925Y199000D03*
X1714175Y187000D03*
X1721500Y205000D03*
X1721600Y194760D03*
Y198500D03*
X1767525Y114016D03*
X1759600Y114500D03*
X1767425Y107000D03*
X1761600Y124524D03*
X1764000Y142525D03*
X1767425Y137000D03*
X1768500Y142525D03*
X1764100Y119500D03*
X1764000Y158025D03*
X1759925Y178900D03*
X1768500Y158025D03*
X1763925Y170984D03*
Y155484D03*
X1766925Y181500D03*
X1769425Y203000D03*
X1754925D03*
X1750563Y198000D03*
X1747925Y204000D03*
X1751600Y258000D03*
Y255500D03*
X1740600Y258000D03*
Y255500D03*
Y248000D03*
Y250500D03*
Y253000D03*
X1751600D03*
Y250500D03*
Y248000D03*
X1766432Y250301D03*
Y247301D03*
X1769300Y329400D03*
Y340600D03*
X1769692Y334649D03*
X1767700Y346200D03*
X1767600Y350000D03*
X1772975Y109500D03*
Y104500D03*
X1773076Y117500D03*
X1773000Y142525D03*
X1773500Y129500D03*
X1772975Y124500D03*
X1773000Y158000D03*
X1772600Y177300D03*
X1800100Y187500D03*
X1778000Y189500D03*
X1789600Y247000D03*
X1783932Y250357D03*
Y247357D03*
X1775432Y250357D03*
Y247357D03*
X1795600Y308000D03*
X1777375Y356300D03*
X1777383Y352305D03*
X1784035Y389535D03*
X1781535D03*
X1784035Y386935D03*
X1781535D03*
X1778838Y389508D03*
Y386908D03*
X1781535Y402935D03*
X1784035D03*
X1778838Y402908D03*
X1781535Y405535D03*
X1784035D03*
X1778838Y405508D03*
X1817500Y188000D03*
X1809600Y195000D03*
X1811500Y186000D03*
X1842164Y419238D03*
X1847164D03*
X1837164D03*
X1852164D03*
X1842164Y432338D03*
X1847164Y430568D03*
X1852164Y435538D03*
X1837164Y428238D03*
G54D20*
X166785Y230000D03*
Y310000D03*
Y390000D03*
Y470000D03*
Y550000D03*
X243785Y230000D03*
Y310000D03*
Y390000D03*
Y470000D03*
Y550000D03*
X1488500Y230000D03*
Y310000D03*
Y390000D03*
Y470000D03*
Y550000D03*
X1565500Y230000D03*
Y310000D03*
Y390000D03*
Y470000D03*
Y550000D03*
G54D47*
X1846142Y270433D03*
X1856772D03*
X1846142Y280433D03*
Y290433D03*
Y300433D03*
X1856772D03*
Y290433D03*
Y280433D03*
X1848957Y324213D03*
X1843957Y329213D03*
X1848957Y314213D03*
X1843957Y319213D03*
X1853957Y329213D03*
Y319213D03*
X1848957Y334213D03*
Y344213D03*
X1843957Y339213D03*
Y349213D03*
X1853957D03*
Y339213D03*
X1858957Y344213D03*
Y334213D03*
G54D15*
X45275Y236614D03*
Y411594D03*
X72835Y236614D03*
X68898Y226771D03*
X59055Y222834D03*
X49212Y226771D03*
X68898Y246457D03*
X49212D03*
X59055Y250394D03*
X68898Y421437D03*
X72835Y411594D03*
X68898Y401751D03*
X59055Y397814D03*
X49212Y401751D03*
Y421437D03*
X59055Y425374D03*
X1673228Y222834D03*
X1663385Y226771D03*
X1659448Y236614D03*
X1663385Y246457D03*
X1673228Y250394D03*
Y397834D03*
X1663385Y401771D03*
X1659448Y411614D03*
X1663385Y421457D03*
X1673228Y425394D03*
X1687008Y236614D03*
X1683071Y226771D03*
Y246457D03*
Y421457D03*
X1687008Y411614D03*
X1683071Y401771D03*
G54D42*
X1642915Y111950D03*
X1639372Y114450D03*
X1646458Y111950D03*
X1642915Y114450D03*
X1639372Y111950D03*
X1646458Y114450D03*
X1650002Y111950D03*
Y114450D03*
G54D28*
X468946Y338216D03*
X465946D03*
X468946Y341216D03*
X465946D03*
X458946Y338216D03*
X455946D03*
X458946Y341216D03*
X455946D03*
Y357216D03*
X458946D03*
X468946Y357016D03*
X465946D03*
X471946Y338216D03*
Y341216D03*
X481446Y338216D03*
X478446D03*
X481446Y341216D03*
X478446D03*
X484446Y338216D03*
Y341216D03*
X471946Y357016D03*
X528084Y77900D03*
Y74900D03*
Y71900D03*
X525084Y77900D03*
Y74900D03*
Y71900D03*
X522084Y77900D03*
Y74900D03*
Y71900D03*
X525084Y116300D03*
X522084D03*
X528084D03*
X525084Y122300D03*
X522084D03*
X525084Y119300D03*
X522084D03*
X528084Y122300D03*
Y119300D03*
X525084Y166700D03*
X522084D03*
X525084Y160700D03*
Y163700D03*
X522084D03*
Y160700D03*
Y205100D03*
Y208100D03*
X525084D03*
Y205100D03*
X522084Y211100D03*
X525084D03*
X522084Y249500D03*
Y252500D03*
X525084D03*
Y249500D03*
X522084Y255500D03*
X525084D03*
X528084Y252500D03*
Y249500D03*
Y255500D03*
Y299900D03*
X525084D03*
X522084D03*
X528084Y296900D03*
X525084D03*
X522084D03*
X528084Y293900D03*
X525084D03*
X522084D03*
X531084Y77900D03*
Y74900D03*
Y71900D03*
Y299900D03*
Y296900D03*
Y293900D03*
X586184Y117800D03*
X583184D03*
X580184D03*
X586184Y114800D03*
X583184D03*
X580184D03*
X586184Y111800D03*
X583184D03*
X580184D03*
X586184Y108800D03*
X583184D03*
X580184D03*
X586184Y105800D03*
X583184D03*
X580184D03*
Y126800D03*
X583184D03*
X586184D03*
Y123800D03*
X583184D03*
X580184D03*
X586184Y120800D03*
X583184D03*
X580184D03*
X583184Y239000D03*
X580184D03*
X583184Y242000D03*
X580184D03*
X583184Y254000D03*
Y251000D03*
Y248000D03*
Y245000D03*
X580184D03*
Y248000D03*
Y251000D03*
Y254000D03*
X583184Y260000D03*
Y257000D03*
X580184D03*
Y260000D03*
X620466Y246839D03*
X664484Y212500D03*
X666984D03*
X672484D03*
X674984D03*
X679484D03*
X681984D03*
X685484D03*
X687984D03*
X1240200Y77900D03*
Y74900D03*
Y71900D03*
Y68900D03*
Y65900D03*
X1237200D03*
Y68900D03*
Y71900D03*
Y74900D03*
Y77900D03*
X1234200Y65900D03*
Y68900D03*
Y71900D03*
Y74900D03*
Y77900D03*
X1231200Y65900D03*
Y68900D03*
Y71900D03*
Y74900D03*
Y77900D03*
X1234200Y116300D03*
Y113300D03*
Y110300D03*
X1237200Y116300D03*
Y113300D03*
Y110300D03*
X1240200D03*
Y113300D03*
Y116300D03*
X1234200Y122300D03*
Y119300D03*
X1237200Y122300D03*
Y119300D03*
X1240200D03*
Y122300D03*
X1237200Y166700D03*
Y163700D03*
Y160700D03*
Y157700D03*
Y154700D03*
X1240200D03*
Y157700D03*
Y160700D03*
Y163700D03*
Y166700D03*
X1237200Y208100D03*
X1240200D03*
X1237200Y211100D03*
X1240200D03*
X1234200Y252500D03*
X1237200D03*
X1234200Y255500D03*
X1237200D03*
X1240200Y252500D03*
Y255500D03*
Y299900D03*
Y296900D03*
X1237200D03*
Y299900D03*
X1234200Y296900D03*
Y299900D03*
X1231200Y296900D03*
Y299900D03*
X1657050Y102380D03*
X1685100Y127500D03*
X1692600Y135975D03*
X1751600Y238000D03*
Y235500D03*
X1740600D03*
Y238000D03*
X1751600Y233000D03*
X1740600D03*
X1766447Y239798D03*
Y242798D03*
X1751600Y240500D03*
X1740600D03*
X1783947Y239798D03*
Y242798D03*
X1775447Y239798D03*
Y242798D03*
X1789600Y243500D03*
G54D29*
X649059Y314000D03*
X1491918Y107773D03*
Y110773D03*
Y113773D03*
Y104773D03*
X1488918D03*
Y113773D03*
Y110773D03*
Y107773D03*
X1485918Y104773D03*
Y113773D03*
Y110773D03*
Y107773D03*
X1482918Y104773D03*
Y113773D03*
Y110773D03*
Y107773D03*
X1618800Y76700D03*
X1615800Y82700D03*
Y79700D03*
Y76700D03*
X1618800Y79700D03*
Y82700D03*
X1727200Y104500D03*
X1728600Y387500D03*
X1731100D03*
X1733600D03*
X1770575Y137000D03*
X1762454Y320347D03*
X1742109Y345235D03*
Y342435D03*
X1747416Y348293D03*
X1747909Y345335D03*
Y342535D03*
X1744909Y345335D03*
Y342535D03*
X1742109Y339635D03*
Y336835D03*
Y334035D03*
X1747909Y339735D03*
Y336935D03*
Y334135D03*
X1744909Y339735D03*
Y336935D03*
Y334135D03*
X1767151Y333311D03*
X1777532Y328322D03*
X1777459Y332322D03*
X1777383Y348288D03*
G54D34*
X802087Y200984D03*
X792087D03*
X822087D03*
X812087D03*
X920197D03*
X910197D03*
X940197D03*
X930197D03*
G54D37*
X825900Y362200D03*
Y372200D03*
X866400Y362200D03*
Y382200D03*
X906900Y362200D03*
Y372200D03*
G54D21*
X163878Y601693D03*
X156004D03*
X163878Y609567D03*
Y617441D03*
Y625315D03*
Y633189D03*
X156004Y609567D03*
Y617441D03*
Y625315D03*
Y633189D03*
X163878Y641063D03*
Y648937D03*
Y656811D03*
X156004Y641063D03*
Y648937D03*
Y656811D03*
X163878Y664685D03*
X156004D03*
X1587107Y601693D03*
Y609567D03*
Y617441D03*
Y625315D03*
Y633189D03*
Y641063D03*
Y648937D03*
Y656811D03*
Y664685D03*
X1594981Y601693D03*
Y609567D03*
Y617441D03*
Y625315D03*
Y633189D03*
Y641063D03*
Y648937D03*
Y656811D03*
Y664685D03*
G54D31*
X681498Y575042D03*
Y565042D03*
X681604Y593187D03*
Y603187D03*
X997833Y575042D03*
Y565042D03*
Y593187D03*
Y603187D03*
G54D43*
X1848583Y99212D03*
X1848582Y481693D03*
G54D18*
X137303Y601693D03*
Y609567D03*
Y617441D03*
Y625315D03*
Y633189D03*
Y641063D03*
Y648937D03*
Y656811D03*
Y664685D03*
X145177Y601693D03*
Y609567D03*
Y617441D03*
Y625315D03*
Y633189D03*
Y641063D03*
Y648937D03*
Y656811D03*
Y664685D03*
X192126Y633189D03*
Y625315D03*
Y617441D03*
X200000Y633189D03*
Y625315D03*
Y617441D03*
X215748Y633189D03*
Y625315D03*
Y617441D03*
X223622Y633189D03*
Y625315D03*
Y617441D03*
X250866Y10197D03*
X255906Y617441D03*
X248032D03*
X255906Y625315D03*
Y633189D03*
X248032D03*
Y625315D03*
X279646Y23012D03*
Y13012D03*
X274646Y18012D03*
X284646Y8012D03*
X274646D03*
X260866Y10197D03*
X279528Y617441D03*
X271654D03*
X279528Y625315D03*
Y633189D03*
X271654D03*
Y625315D03*
X289646Y23012D03*
Y13012D03*
X295276Y617441D03*
Y625315D03*
Y633189D03*
X303150D03*
Y625315D03*
Y617441D03*
X1437008D03*
X1429134D03*
X1437008Y625315D03*
Y633189D03*
X1429134D03*
Y625315D03*
X1465197Y18012D03*
Y8012D03*
X1451417Y10197D03*
X1441417D03*
X1460630Y617441D03*
X1452756D03*
X1460630Y625315D03*
Y633189D03*
X1452756D03*
Y625315D03*
X1480197Y23012D03*
X1470197D03*
X1480197Y13012D03*
X1470197D03*
X1475197Y8012D03*
X1476378Y617441D03*
Y625315D03*
Y633189D03*
X1484252D03*
Y625315D03*
Y617441D03*
X1508661Y633189D03*
Y625315D03*
Y617441D03*
X1516535Y633189D03*
Y625315D03*
Y617441D03*
X1532283Y633189D03*
Y625315D03*
Y617441D03*
X1540157Y633189D03*
Y625315D03*
Y617441D03*
X1576280Y601693D03*
X1568406D03*
X1576280Y609567D03*
Y617441D03*
Y625315D03*
Y633189D03*
X1568406Y609567D03*
Y617441D03*
Y625315D03*
Y633189D03*
X1576280Y641063D03*
Y648937D03*
Y656811D03*
X1568406Y641063D03*
Y648937D03*
Y656811D03*
X1576280Y664685D03*
X1568406D03*
G54D45*
X1846142Y230433D03*
Y240433D03*
X1856772D03*
Y230433D03*
X1846142Y250433D03*
Y260433D03*
X1856772D03*
Y250433D03*
X1858957Y324213D03*
Y314213D03*
G54D38*
X825900Y382200D03*
X906900D03*
G54D41*
X1011017Y598187D03*
G54D40*
Y570042D03*
G54D25*
X207874Y639095D03*
X1524409D03*
G54D14*
X47244Y17716D03*
Y330708D03*
X279528Y53148D03*
X314961Y561023D03*
X393702Y344488D03*
X748032Y64961D03*
Y344488D03*
X984252Y64961D03*
Y344488D03*
X1338584D03*
X1417324Y561023D03*
X1452756Y53149D03*
X1685040Y17716D03*
Y330708D03*
X1799212Y96457D03*
Y478346D03*
G54D27*
X287402Y628465D03*
X263780Y659961D03*
X1468504Y628465D03*
X1444882Y659961D03*
G54D10*
X19685Y-774040D03*
Y766166D03*
X240866Y15512D03*
X300866Y10197D03*
X566575Y463701D03*
D03*
D03*
X1431417Y15512D03*
X1491417Y10197D03*
X1854331Y-774040D03*
Y766166D03*
G54D46*
X1851457Y220433D03*
X1856772Y360433D03*
G54D23*
X231600Y81000D03*
X1212478Y300181D03*
X1529100Y78500D03*
G54D35*
X822087Y88484D03*
Y313484D03*
X940197Y88484D03*
Y313484D03*
G54D22*
X192126Y656811D03*
Y648937D03*
Y664685D03*
X215748Y656811D03*
Y648937D03*
X223622Y656811D03*
Y648937D03*
X200000Y656811D03*
Y648937D03*
X215748Y664685D03*
X223622D03*
X200000D03*
X255906Y648937D03*
X248032D03*
X255906Y656811D03*
X248032D03*
X255906Y664685D03*
X248032D03*
X279528Y648937D03*
X271654D03*
X279528Y656811D03*
X271654D03*
X279528Y664685D03*
X271654D03*
X303150Y648937D03*
X295276D03*
X303150Y656811D03*
X295276D03*
X303150Y664685D03*
X295276D03*
X1437008Y648937D03*
X1429134D03*
X1437008Y656811D03*
X1429134D03*
X1437008Y664685D03*
X1429134D03*
X1460630Y648937D03*
X1452756D03*
X1460630Y656811D03*
X1452756D03*
X1460630Y664685D03*
X1452756D03*
X1484252Y648937D03*
X1476378D03*
X1484252Y656811D03*
X1476378D03*
X1484252Y664685D03*
X1476378D03*
X1508661Y656811D03*
Y648937D03*
X1516535Y656811D03*
Y648937D03*
X1508661Y664685D03*
X1516535D03*
X1532283Y656811D03*
Y648937D03*
X1540157Y656811D03*
Y648937D03*
X1532283Y664685D03*
X1540157D03*
G54D26*
X250866Y20827D03*
X284646Y18012D03*
X260866Y20827D03*
X1451417D03*
X1441417D03*
X1475197Y18012D03*
G54D24*
X225829Y103412D03*
Y99503D03*
X225953Y95780D03*
X225891Y92305D03*
X229829Y103412D03*
X233329D03*
X237329D03*
X229829Y99503D03*
X233329D03*
X237329D03*
X229953Y95780D03*
X233453D03*
X237453D03*
X229891Y92305D03*
X233391D03*
X237391D03*
X622288Y235790D03*
X624788D03*
X1635000Y152925D03*
X1733600Y397500D03*
X1731100D03*
X1728600D03*
G54D11*
X3018Y23930D03*
X10493Y5830D03*
X3018Y43930D03*
Y83930D03*
Y63930D03*
Y103930D03*
Y143930D03*
Y123930D03*
Y163930D03*
Y203930D03*
Y183930D03*
Y223930D03*
Y263930D03*
Y243930D03*
Y283930D03*
Y323930D03*
Y303930D03*
Y343930D03*
Y383930D03*
Y363930D03*
Y403930D03*
Y443930D03*
Y423930D03*
Y463930D03*
Y503930D03*
Y483930D03*
Y523930D03*
Y563930D03*
Y543930D03*
Y583930D03*
X15642Y619715D03*
X3018Y603930D03*
X30709Y3014D03*
X35455Y620194D03*
X75455D03*
X55455D03*
X81406Y3042D03*
X101406D03*
X95455Y620194D03*
X121406Y3042D03*
X137355Y120500D03*
X114923Y623982D03*
X124901Y640105D03*
X161406Y3042D03*
X141406D03*
X154778Y672779D03*
X181406Y3042D03*
X194778Y672779D03*
X174778D03*
X201406Y3042D03*
X221406D03*
X205061Y85500D03*
Y79000D03*
Y75000D03*
Y71500D03*
Y67500D03*
Y89500D03*
Y93000D03*
Y97000D03*
X200600Y109059D03*
X205100Y123000D03*
X214778Y672779D03*
X254778D03*
X234778D03*
X274778D03*
X314766Y39211D03*
X317766D03*
X311956Y651522D03*
X294778Y672779D03*
X323766Y39211D03*
X320766D03*
X324000Y77000D03*
X321000Y63000D03*
X345412Y435017D03*
Y455017D03*
Y475017D03*
Y495017D03*
Y515017D03*
Y535017D03*
Y555017D03*
Y575017D03*
Y595017D03*
X342119Y613510D03*
X331285Y620008D03*
X369192Y38417D03*
X372192D03*
X378192D03*
X375192D03*
X362127Y406608D03*
X350024Y418335D03*
X408100Y180100D03*
Y224500D03*
X399680Y402510D03*
X379680D03*
X419680D03*
X459680D03*
X439680D03*
X498923Y37456D03*
X495923D03*
X492923D03*
X489923D03*
X479680Y402510D03*
X501923Y37456D03*
X504923D03*
X510923D03*
X507923D03*
X528084Y68900D03*
Y65900D03*
X525084Y68900D03*
Y65900D03*
X522084Y68900D03*
Y65900D03*
X525084Y113300D03*
Y110300D03*
X522084Y113300D03*
Y110300D03*
X528084Y113300D03*
Y110300D03*
X525084Y157700D03*
Y154700D03*
X522084Y157700D03*
Y154700D03*
Y199100D03*
Y202100D03*
X525084Y199100D03*
Y202100D03*
X522084Y243500D03*
Y246500D03*
X525084Y243500D03*
Y246500D03*
X528084Y243500D03*
Y246500D03*
Y290900D03*
Y287900D03*
X525084D03*
Y290900D03*
X522084D03*
Y287900D03*
X499680Y402510D03*
X519680D03*
X531084Y68900D03*
Y65900D03*
Y290900D03*
Y287900D03*
X539680Y402510D03*
X559680D03*
X579680D03*
X601675Y305575D03*
X619680Y402510D03*
X599680D03*
X645784Y43500D03*
X648784D03*
X645784Y40500D03*
X648784D03*
X645784Y99000D03*
X648784D03*
X645784Y96000D03*
X648784D03*
X641000Y261500D03*
X639680Y402510D03*
X651784Y43500D03*
Y40500D03*
X657784D03*
X654784D03*
X657784Y43500D03*
X654784D03*
X651784Y99000D03*
Y96000D03*
X657784D03*
X654784D03*
X657784Y99000D03*
X654784D03*
X659000Y284000D03*
X671000Y315760D03*
X668000Y311500D03*
X663500D03*
X657500Y326925D03*
X659680Y402510D03*
X679680D03*
X693863Y189760D03*
X688900Y184260D03*
X704200Y206569D03*
X699680Y402510D03*
X736554Y131056D03*
Y128056D03*
X739554Y131056D03*
Y128056D03*
X742554D03*
X732100Y185000D03*
X729100D03*
X726100D03*
X720100D03*
X723100D03*
X726100Y188000D03*
X729100D03*
X732100D03*
X723100D03*
X720100D03*
X726000Y231500D03*
X729000D03*
X723000D03*
X720000D03*
X732000D03*
Y228500D03*
X720000D03*
X723000D03*
X726000D03*
X729000D03*
X719500Y315500D03*
X734500Y310575D03*
X739680Y402510D03*
X719680D03*
X742554Y131056D03*
X749600Y185000D03*
X752600D03*
X755600D03*
X758600D03*
X746600Y188000D03*
X758600D03*
X755600D03*
X752600D03*
X749600D03*
X746600Y185000D03*
X758500Y231500D03*
X746500D03*
X755500D03*
X752500D03*
X749500D03*
X746500Y228500D03*
X755500D03*
X752500D03*
X749500D03*
X758500D03*
X759680Y402510D03*
X779680D03*
X799680D03*
X819680D03*
X839680D03*
X859680D03*
X880500Y369500D03*
X879680Y402510D03*
X919680D03*
X899680D03*
X939680D03*
X983500Y185000D03*
Y188000D03*
X980500Y185000D03*
X974500D03*
X977500D03*
X980500Y188000D03*
X977500D03*
X974500D03*
Y231500D03*
X977500D03*
X983500D03*
X980500D03*
X983500Y228500D03*
X980500D03*
X977500D03*
X974500D03*
X959680Y402510D03*
X979680D03*
X990954Y131056D03*
Y128056D03*
X993954Y131056D03*
Y128056D03*
X996954D03*
Y131056D03*
X986500Y185000D03*
Y188000D03*
X1004000Y185000D03*
X1001000Y188000D03*
X1004000D03*
X1007000Y185000D03*
X1010000D03*
X1013000D03*
Y188000D03*
X1010000D03*
X1007000D03*
X1001000Y185000D03*
X1004000Y231500D03*
X1007000D03*
X1010000D03*
X1001000D03*
X986500D03*
X1013000D03*
X986500Y228500D03*
X1013000D03*
X1004000D03*
X1007000D03*
X1010000D03*
X1001000D03*
X999680Y402510D03*
X1030100Y207500D03*
X1039680Y402510D03*
X1019680D03*
X1074500Y43500D03*
Y99000D03*
X1059680Y402510D03*
X1077500Y43500D03*
Y40500D03*
X1074500D03*
X1080500D03*
X1083500D03*
X1086500D03*
X1080500Y43500D03*
X1083500D03*
X1086500D03*
X1077500Y99000D03*
Y96000D03*
X1074500D03*
X1080500D03*
X1083500D03*
X1086500D03*
X1080500Y99000D03*
X1083500D03*
X1086500D03*
X1101500Y268500D03*
X1079680Y402510D03*
X1099680D03*
X1118500Y283000D03*
X1106000Y364500D03*
X1112500Y364700D03*
X1122000Y366240D03*
X1119680Y402510D03*
X1155366Y38982D03*
X1152366D03*
X1158366D03*
X1161366D03*
X1143500Y251500D03*
X1141600Y305161D03*
X1154600Y321050D03*
X1143100Y322500D03*
Y320000D03*
X1147000Y342500D03*
X1135000Y366500D03*
X1139000D03*
X1159680Y402510D03*
X1139680D03*
X1176100Y105800D03*
Y108800D03*
X1182100Y105800D03*
Y108800D03*
X1179100D03*
Y105800D03*
X1176100Y111800D03*
Y114800D03*
Y117800D03*
X1182100Y111800D03*
Y114800D03*
Y117800D03*
X1179100D03*
Y114800D03*
Y111800D03*
X1176100Y126800D03*
Y123800D03*
Y120800D03*
X1182100Y126800D03*
Y123800D03*
Y120800D03*
X1179100D03*
Y123800D03*
Y126800D03*
X1176100Y239000D03*
X1171600Y238000D03*
X1179100Y239000D03*
X1182100D03*
X1176100Y254000D03*
Y251000D03*
Y248000D03*
Y245000D03*
Y257000D03*
Y260000D03*
Y242000D03*
X1171600Y241500D03*
X1179100Y242000D03*
Y260000D03*
Y257000D03*
Y245000D03*
Y248000D03*
Y251000D03*
Y254000D03*
X1182100D03*
Y251000D03*
Y248000D03*
Y245000D03*
Y257000D03*
Y260000D03*
Y242000D03*
X1165575Y340500D03*
X1171700Y349900D03*
X1178500Y368740D03*
X1179680Y402510D03*
X1223866Y38482D03*
X1220866D03*
X1225930Y359148D03*
X1199680Y402510D03*
X1219680D03*
X1226866Y38482D03*
X1229866D03*
X1237200Y205100D03*
Y202100D03*
Y199100D03*
X1240200D03*
Y202100D03*
Y205100D03*
X1234200Y249500D03*
Y246500D03*
Y243500D03*
X1237200Y249500D03*
Y246500D03*
Y243500D03*
X1240200D03*
Y246500D03*
Y249500D03*
Y293900D03*
Y290900D03*
Y287900D03*
X1237200D03*
Y290900D03*
Y293900D03*
X1234200Y287900D03*
Y290900D03*
Y293900D03*
X1231200D03*
Y290900D03*
Y287900D03*
X1242930Y359148D03*
Y356148D03*
X1245930Y359148D03*
Y356148D03*
X1248930Y359148D03*
Y356148D03*
X1231930D03*
Y359148D03*
X1228930Y356148D03*
Y359148D03*
X1225930Y356148D03*
X1253930Y379648D03*
X1250930D03*
X1247930D03*
X1239680Y402510D03*
X1264366Y38482D03*
X1261366D03*
X1267366D03*
X1270366D03*
X1260340Y359284D03*
Y356284D03*
X1263340Y359284D03*
Y356284D03*
X1266340Y359284D03*
Y356284D03*
X1286113Y378312D03*
X1265340Y379784D03*
X1268340D03*
X1271340D03*
X1259680Y402510D03*
X1279680D03*
X1313366Y38482D03*
X1307366D03*
X1310366D03*
X1286113Y375312D03*
X1289113Y378312D03*
Y375312D03*
X1292113Y378312D03*
Y375312D03*
Y372312D03*
X1289113D03*
X1299680Y402510D03*
X1316366Y38482D03*
X1339680Y402510D03*
X1319680D03*
X1355310Y38893D03*
X1352310D03*
X1349310D03*
X1358310D03*
X1355100Y160000D03*
X1355000Y204400D03*
X1359620Y402940D03*
X1386882Y434539D03*
Y454539D03*
Y474539D03*
Y494539D03*
Y514539D03*
Y534539D03*
Y554539D03*
Y574539D03*
Y594539D03*
X1389643Y612723D03*
X1403035Y620181D03*
X1422310Y40481D03*
X1419310D03*
X1416310D03*
X1425310D03*
X1420335Y635388D03*
Y655388D03*
X1428754Y670547D03*
X1445829Y672778D03*
X1465829D03*
X1490000Y84000D03*
X1485829Y672778D03*
X1508460Y3003D03*
X1527100Y108500D03*
X1505829Y672778D03*
X1525829D03*
X1548460Y3003D03*
X1528460D03*
X1531600Y96941D03*
X1545829Y672778D03*
X1588460Y3003D03*
X1568460D03*
X1565829Y672778D03*
X1585829D03*
X1608460Y3003D03*
X1609100Y85500D03*
Y82000D03*
X1606100Y85500D03*
Y82000D03*
X1609100Y69500D03*
Y66000D03*
Y62500D03*
X1606100Y69500D03*
Y66000D03*
Y62500D03*
X1602100Y85500D03*
Y82000D03*
Y69500D03*
Y66000D03*
Y62500D03*
X1594930Y115000D03*
X1614100Y110000D03*
Y115000D03*
X1609100Y89000D03*
X1606100D03*
X1602100D03*
X1614100Y120000D03*
Y130000D03*
X1613527Y627220D03*
X1607226Y650448D03*
X1602599Y667628D03*
X1648460Y3003D03*
X1628460D03*
X1629870Y104240D03*
X1647837Y121812D03*
X1638707Y132954D03*
X1623100Y172500D03*
Y178000D03*
X1631585Y188777D03*
X1628658Y620261D03*
X1648675Y620226D03*
X1662000Y106000D03*
X1649197Y132915D03*
X1650990Y122034D03*
X1667000Y138000D03*
X1649500Y173398D03*
X1668075Y189500D03*
X1679176Y194760D03*
X1652600Y212000D03*
X1668675Y620226D03*
X1708460Y3003D03*
X1702525Y129500D03*
X1685976Y148000D03*
Y164500D03*
Y159000D03*
Y153500D03*
Y175500D03*
Y170000D03*
X1701100Y178500D03*
X1685976Y181000D03*
X1702075Y205500D03*
X1688692Y620191D03*
X1708692D03*
X1729255Y25347D03*
Y45347D03*
X1732786Y58461D03*
X1729411Y143661D03*
X1720100Y179500D03*
X1729411Y159161D03*
X1733500Y173760D03*
X1712000Y153000D03*
X1738740Y191500D03*
X1729000Y183500D03*
X1724824Y205276D03*
X1711025Y187000D03*
X1729275Y562751D03*
Y542751D03*
Y582751D03*
Y602751D03*
X1753635Y69037D03*
X1764000Y107000D03*
X1763500Y113000D03*
X1763075Y178900D03*
X1767075Y155484D03*
X1769476Y168500D03*
X1754260Y187260D03*
X1768000D03*
X1746000Y191240D03*
X1751289Y345227D03*
X1747416Y351817D03*
X1747235Y355989D03*
Y359564D03*
Y363689D03*
Y367264D03*
Y371389D03*
Y374964D03*
X1755454Y515746D03*
X1793635Y69037D03*
X1773635D03*
X1773500Y121000D03*
X1772500Y174000D03*
X1770075Y181500D03*
X1776100Y361500D03*
Y371500D03*
Y368500D03*
X1776140Y364405D03*
X1775454Y515746D03*
X1813635Y69037D03*
X1815454Y515746D03*
X1853635Y69037D03*
X1833635D03*
X1844500Y416500D03*
X1847500Y437000D03*
X1835454Y515746D03*
X1855509Y515697D03*
X1871008Y117112D03*
X1871009Y93913D03*
X1871008Y137112D03*
Y177112D03*
Y157112D03*
Y197112D03*
Y237112D03*
Y217112D03*
Y257112D03*
Y297112D03*
Y277112D03*
Y317112D03*
Y357112D03*
Y337112D03*
Y377112D03*
Y417112D03*
Y397112D03*
Y437112D03*
Y477112D03*
Y457112D03*
Y497112D03*
G54D33*
X802087Y145984D03*
X792087D03*
X802087Y135984D03*
X792087D03*
X802087Y180984D03*
X792087D03*
X802087Y170984D03*
X792087D03*
X802087Y230984D03*
X792087D03*
X802087Y220984D03*
X792087D03*
X802087Y265984D03*
X792087D03*
X802087Y255984D03*
X792087D03*
X822087Y145984D03*
X812087D03*
X822087Y135984D03*
X812087D03*
X822087Y180984D03*
X812087D03*
X822087Y170984D03*
X812087D03*
X822087Y230984D03*
X812087D03*
X822087Y220984D03*
X812087D03*
X822087Y265984D03*
X812087D03*
X822087Y255984D03*
X812087D03*
X920197Y145984D03*
X910197D03*
X920197Y135984D03*
X910197D03*
X920197Y180984D03*
X910197D03*
X920197Y170984D03*
X910197D03*
X920197Y230984D03*
X910197D03*
X920197Y220984D03*
X910197D03*
X920197Y265984D03*
X910197D03*
X920197Y255984D03*
X910197D03*
X940197Y145984D03*
X930197D03*
X940197Y135984D03*
X930197D03*
X940197Y180984D03*
X930197D03*
X940197Y170984D03*
X930197D03*
X940197Y230984D03*
X930197D03*
X940197Y220984D03*
X930197D03*
X940197Y265984D03*
X930197D03*
X940197Y255984D03*
X930197D03*
G54D36*
X822087Y88484D03*
Y313484D03*
X940197Y88484D03*
Y313484D03*
G54D16*
X59055Y236614D03*
Y411594D03*
X1673228Y236614D03*
Y411614D03*
G54D44*
X1835739Y99212D03*
X1835738Y481693D03*
G54D12*
X32284Y541339D03*
X59055Y498032D03*
X1673228D03*
X1700000Y541339D03*
G54D39*
X866400Y372200D03*
G54D30*
X668314Y570042D03*
G54D32*
X668420Y598187D03*
%LPC*%
G75*
G54D19*
X166785Y200472D03*
Y280472D03*
Y360472D03*
Y440472D03*
Y520472D03*
X243785Y200472D03*
Y280472D03*
Y360472D03*
Y440472D03*
Y520472D03*
X1488500Y200472D03*
Y280472D03*
Y360472D03*
Y440472D03*
Y520472D03*
X1565500Y200472D03*
Y280472D03*
Y360472D03*
Y440472D03*
Y520472D03*
G54D48*
G01X169956Y197301D02*
X166785Y200472D01*
G01D02*
X163614Y203643D01*
G01X169956D02*
X166785Y200472D01*
G01D02*
X163614Y197301D01*
G01X169956Y277301D02*
X166785Y280472D01*
G01D02*
X163614Y283643D01*
G01X169956D02*
X166785Y280472D01*
G01D02*
X163614Y277301D01*
G01X166785Y360472D02*
X163614Y357301D01*
G01X169956D02*
X166785Y360472D01*
G01D02*
X163614Y363643D01*
G01X169956D02*
X166785Y360472D01*
G01X169956Y437301D02*
X166785Y440472D01*
G01D02*
X163614Y443643D01*
G01X169956D02*
X166785Y440472D01*
G01D02*
X163614Y437301D01*
G01X166785Y520472D02*
X163614Y517301D01*
G01X169956Y523643D02*
X166785Y520472D01*
G01D02*
X163614Y523643D01*
G01X169956Y517301D02*
X166785Y520472D01*
G01X246956Y197301D02*
X243785Y200472D01*
G01D02*
X240614Y203643D01*
G01X246956D02*
X243785Y200472D01*
G01D02*
X240614Y197301D01*
G01X246956Y277301D02*
X243785Y280472D01*
G01D02*
X240614Y283643D01*
G01X246956D02*
X243785Y280472D01*
G01D02*
X240614Y277301D01*
G01X246956Y357301D02*
X243785Y360472D01*
G01D02*
X240614Y363643D01*
G01X246956D02*
X243785Y360472D01*
G01D02*
X240614Y357301D01*
G01X246956Y437301D02*
X243785Y440472D01*
G01D02*
X240614Y443643D01*
G01X246956D02*
X243785Y440472D01*
G01D02*
X240614Y437301D01*
G01X246956Y517301D02*
X243785Y520472D01*
G01D02*
X240614Y523643D01*
G01X246956D02*
X243785Y520472D01*
G01D02*
X240614Y517301D01*
G01X1491671Y197301D02*
X1488500Y200472D01*
G01D02*
X1485329Y203643D01*
G01X1491671D02*
X1488500Y200472D01*
G01D02*
X1485329Y197301D01*
G01X1491671Y277301D02*
X1488500Y280472D01*
G01D02*
X1485329Y283643D01*
G01X1491671D02*
X1488500Y280472D01*
G01D02*
X1485329Y277301D01*
G01X1491671Y357301D02*
X1488500Y360472D01*
G01D02*
X1485329Y363643D01*
G01X1491671D02*
X1488500Y360472D01*
G01D02*
X1485329Y357301D01*
G01X1491671Y437301D02*
X1488500Y440472D01*
G01D02*
X1485329Y443643D01*
G01X1491671D02*
X1488500Y440472D01*
G01D02*
X1485329Y437301D01*
G01X1491671Y517301D02*
X1488500Y520472D01*
G01D02*
X1485329Y523643D01*
G01X1491671D02*
X1488500Y520472D01*
G01D02*
X1485329Y517301D01*
G01X1568671Y197301D02*
X1565500Y200472D01*
G01D02*
X1562329Y203643D01*
G01X1568671D02*
X1565500Y200472D01*
G01D02*
X1562329Y197301D01*
G01X1568671Y277301D02*
X1565500Y280472D01*
G01D02*
X1562329Y283643D01*
G01X1568671D02*
X1565500Y280472D01*
G01D02*
X1562329Y277301D01*
G01X1568671Y357301D02*
X1565500Y360472D01*
G01D02*
X1562329Y363643D01*
G01X1568671D02*
X1565500Y360472D01*
G01D02*
X1562329Y357301D01*
G01X1568671Y437301D02*
X1565500Y440472D01*
G01D02*
X1562329Y443643D01*
G01X1568671D02*
X1565500Y440472D01*
G01D02*
X1562329Y437301D01*
G01X1568671Y517301D02*
X1565500Y520472D01*
G01D02*
X1562329Y523643D01*
G01X1568671D02*
X1565500Y520472D01*
G01D02*
X1562329Y517301D01*
G54D49*
G01X-457143Y-1211429D02*
Y2242857D01*
X4308572D01*
Y-1211429D01*
X-457143D01*
G01X37000Y-995000D02*
Y-1070000D01*
X537000D01*
Y-995000D01*
X37000D01*
G01X49000Y-1060000D02*
Y-1065000D01*
G01X47543Y-1060000D02*
X50457D01*
G01X55367Y-1065000D02*
X52833D01*
Y-1060000D01*
X55367D01*
G01X54353Y-1062417D02*
X52833D01*
G01X57933Y-1060000D02*
Y-1065000D01*
X60467D01*
G01X64300Y-1065167D02*
X64173Y-1065083D01*
Y-1064917D01*
X64300Y-1064833D01*
X64427Y-1064917D01*
Y-1065083D01*
X64300Y-1065167D01*
G01Y-1062917D02*
X64173Y-1062833D01*
Y-1062667D01*
X64300Y-1062583D01*
X64427Y-1062667D01*
Y-1062833D01*
X64300Y-1062917D01*
G01X69083Y-1066667D02*
X68450Y-1065833D01*
X68133Y-1065000D01*
Y-1061667D01*
X68450Y-1060833D01*
X69083Y-1060000D01*
G01X74500D02*
X73993Y-1060167D01*
X73613Y-1060583D01*
X73360Y-1061083D01*
X73170Y-1061750D01*
X73107Y-1062500D01*
X73170Y-1063250D01*
X73360Y-1063917D01*
X73613Y-1064417D01*
X73993Y-1064833D01*
X74500Y-1065000D01*
X75007Y-1064833D01*
X75387Y-1064417D01*
X75640Y-1063917D01*
X75830Y-1063250D01*
X75893Y-1062500D01*
X75830Y-1061750D01*
X75640Y-1061083D01*
X75387Y-1060583D01*
X75007Y-1060167D01*
X74500Y-1060000D01*
G01X78207Y-1064000D02*
X78587Y-1064583D01*
X79093Y-1064917D01*
X79663Y-1065000D01*
X80170Y-1064917D01*
X80677Y-1064500D01*
X80993Y-1064000D01*
X81057Y-1063500D01*
X80930Y-1062917D01*
X80487Y-1062500D01*
X80043Y-1062333D01*
X79473D01*
G01X80043D02*
X80423Y-1062083D01*
X80740Y-1061667D01*
X80867Y-1061167D01*
X80740Y-1060667D01*
X80423Y-1060250D01*
X79853Y-1060000D01*
X79283Y-1060083D01*
X78713Y-1060417D01*
G01X85017Y-1066667D02*
X85650Y-1065833D01*
X85967Y-1065000D01*
Y-1061667D01*
X85650Y-1060833D01*
X85017Y-1060000D01*
G01X88407Y-1064000D02*
X88787Y-1064583D01*
X89293Y-1064917D01*
X89863Y-1065000D01*
X90370Y-1064917D01*
X90877Y-1064500D01*
X91193Y-1064000D01*
X91257Y-1063500D01*
X91130Y-1062917D01*
X90687Y-1062500D01*
X90243Y-1062333D01*
X89673D01*
G01X90243D02*
X90623Y-1062083D01*
X90940Y-1061667D01*
X91067Y-1061167D01*
X90940Y-1060667D01*
X90623Y-1060250D01*
X90053Y-1060000D01*
X89483Y-1060083D01*
X88913Y-1060417D01*
G01X93697Y-1060833D02*
X94077Y-1060333D01*
X94520Y-1060083D01*
X95027Y-1060000D01*
X95660Y-1060167D01*
X96103Y-1060583D01*
X96230Y-1061083D01*
X96167Y-1061583D01*
X95913Y-1062000D01*
X94647Y-1062833D01*
X94077Y-1063417D01*
X93697Y-1064250D01*
X93570Y-1065000D01*
X96230D01*
G01X99873D02*
X100000Y-1063917D01*
X100190Y-1063000D01*
X100443Y-1062167D01*
X100760Y-1061250D01*
X101267Y-1060000D01*
X98733D01*
G01X104277Y-1063333D02*
X105923D01*
G01X108997Y-1060833D02*
X109377Y-1060333D01*
X109820Y-1060083D01*
X110327Y-1060000D01*
X110960Y-1060167D01*
X111403Y-1060583D01*
X111530Y-1061083D01*
X111467Y-1061583D01*
X111213Y-1062000D01*
X109947Y-1062833D01*
X109377Y-1063417D01*
X108997Y-1064250D01*
X108870Y-1065000D01*
X111530D01*
G01X113907Y-1064000D02*
X114287Y-1064583D01*
X114793Y-1064917D01*
X115363Y-1065000D01*
X115870Y-1064917D01*
X116377Y-1064500D01*
X116693Y-1064000D01*
X116757Y-1063500D01*
X116630Y-1062917D01*
X116187Y-1062500D01*
X115743Y-1062333D01*
X115173D01*
G01X115743D02*
X116123Y-1062083D01*
X116440Y-1061667D01*
X116567Y-1061167D01*
X116440Y-1060667D01*
X116123Y-1060250D01*
X115553Y-1060000D01*
X114983Y-1060083D01*
X114413Y-1060417D01*
G01X121160Y-1065000D02*
Y-1060000D01*
X118817Y-1063583D01*
X121983D01*
G01X124107Y-1064250D02*
X124487Y-1064667D01*
X124930Y-1064917D01*
X125500Y-1065000D01*
X126070Y-1064833D01*
X126513Y-1064500D01*
X126830Y-1063917D01*
X126893Y-1063250D01*
X126767Y-1062583D01*
X126450Y-1062167D01*
X126007Y-1061833D01*
X125563Y-1061750D01*
X125120Y-1061833D01*
X124550Y-1062167D01*
X124740Y-1060000D01*
X126450D01*
G01X134497Y-1065000D02*
Y-1060000D01*
X136903D01*
G01X136017Y-1062417D02*
X134497D01*
G01X139217Y-1065000D02*
X140800Y-1060000D01*
X142383Y-1065000D01*
G01X141813Y-1063250D02*
X139787D01*
G01X144570Y-1065000D02*
X147230Y-1060000D01*
G01X144570D02*
X147230Y-1065000D01*
G01X151000Y-1065167D02*
X150873Y-1065083D01*
Y-1064917D01*
X151000Y-1064833D01*
X151127Y-1064917D01*
Y-1065083D01*
X151000Y-1065167D01*
G01Y-1062917D02*
X150873Y-1062833D01*
Y-1062667D01*
X151000Y-1062583D01*
X151127Y-1062667D01*
Y-1062833D01*
X151000Y-1062917D01*
G01X155783Y-1066667D02*
X155150Y-1065833D01*
X154833Y-1065000D01*
Y-1061667D01*
X155150Y-1060833D01*
X155783Y-1060000D01*
G01X161200D02*
X160693Y-1060167D01*
X160313Y-1060583D01*
X160060Y-1061083D01*
X159870Y-1061750D01*
X159807Y-1062500D01*
X159870Y-1063250D01*
X160060Y-1063917D01*
X160313Y-1064417D01*
X160693Y-1064833D01*
X161200Y-1065000D01*
X161707Y-1064833D01*
X162087Y-1064417D01*
X162340Y-1063917D01*
X162530Y-1063250D01*
X162593Y-1062500D01*
X162530Y-1061750D01*
X162340Y-1061083D01*
X162087Y-1060583D01*
X161707Y-1060167D01*
X161200Y-1060000D01*
G01X164907Y-1064000D02*
X165287Y-1064583D01*
X165793Y-1064917D01*
X166363Y-1065000D01*
X166870Y-1064917D01*
X167377Y-1064500D01*
X167693Y-1064000D01*
X167757Y-1063500D01*
X167630Y-1062917D01*
X167187Y-1062500D01*
X166743Y-1062333D01*
X166173D01*
G01X166743D02*
X167123Y-1062083D01*
X167440Y-1061667D01*
X167567Y-1061167D01*
X167440Y-1060667D01*
X167123Y-1060250D01*
X166553Y-1060000D01*
X165983Y-1060083D01*
X165413Y-1060417D01*
G01X171717Y-1066667D02*
X172350Y-1065833D01*
X172667Y-1065000D01*
Y-1061667D01*
X172350Y-1060833D01*
X171717Y-1060000D01*
G01X175107Y-1064000D02*
X175487Y-1064583D01*
X175993Y-1064917D01*
X176563Y-1065000D01*
X177070Y-1064917D01*
X177577Y-1064500D01*
X177893Y-1064000D01*
X177957Y-1063500D01*
X177830Y-1062917D01*
X177387Y-1062500D01*
X176943Y-1062333D01*
X176373D01*
G01X176943D02*
X177323Y-1062083D01*
X177640Y-1061667D01*
X177767Y-1061167D01*
X177640Y-1060667D01*
X177323Y-1060250D01*
X176753Y-1060000D01*
X176183Y-1060083D01*
X175613Y-1060417D01*
G01X180523Y-1064417D02*
X180967Y-1064833D01*
X181473Y-1065000D01*
X181980Y-1064833D01*
X182423Y-1064333D01*
X182740Y-1063583D01*
X182867Y-1062833D01*
Y-1061917D01*
X182740Y-1061167D01*
X182423Y-1060500D01*
X182043Y-1060167D01*
X181600Y-1060000D01*
X181093Y-1060167D01*
X180713Y-1060500D01*
X180460Y-1061000D01*
X180333Y-1061667D01*
X180460Y-1062250D01*
X180777Y-1062833D01*
X181157Y-1063167D01*
X181600Y-1063250D01*
X182107Y-1063083D01*
X182487Y-1062667D01*
X182867Y-1061917D01*
G01X186573Y-1065000D02*
X186700Y-1063917D01*
X186890Y-1063000D01*
X187143Y-1062167D01*
X187460Y-1061250D01*
X187967Y-1060000D01*
X185433D01*
G01X190977Y-1063333D02*
X192623D01*
G01X195507Y-1064000D02*
X195887Y-1064583D01*
X196393Y-1064917D01*
X196963Y-1065000D01*
X197470Y-1064917D01*
X197977Y-1064500D01*
X198293Y-1064000D01*
X198357Y-1063500D01*
X198230Y-1062917D01*
X197787Y-1062500D01*
X197343Y-1062333D01*
X196773D01*
G01X197343D02*
X197723Y-1062083D01*
X198040Y-1061667D01*
X198167Y-1061167D01*
X198040Y-1060667D01*
X197723Y-1060250D01*
X197153Y-1060000D01*
X196583Y-1060083D01*
X196013Y-1060417D01*
G01X200797Y-1062917D02*
X201240Y-1062333D01*
X201620Y-1062000D01*
X202127Y-1061833D01*
X202570Y-1062000D01*
X202887Y-1062333D01*
X203140Y-1062833D01*
X203203Y-1063417D01*
X203140Y-1063917D01*
X202887Y-1064417D01*
X202507Y-1064833D01*
X202063Y-1065000D01*
X201557Y-1064833D01*
X201113Y-1064333D01*
X200860Y-1063583D01*
X200797Y-1062750D01*
X200923Y-1061667D01*
X201113Y-1061083D01*
X201430Y-1060500D01*
X201873Y-1060083D01*
X202317Y-1060000D01*
X202760Y-1060167D01*
X203077Y-1060583D01*
G01X207100Y-1065000D02*
Y-1060000D01*
X206340Y-1061000D01*
G01Y-1065000D02*
X207860D01*
G01X212960D02*
Y-1060000D01*
X210617Y-1063583D01*
X213783D01*
G01X232000Y-995000D02*
Y-1070000D01*
G01Y-1045000D02*
X335000D01*
Y-1020000D01*
G01X232000D02*
X335000D01*
G01X337000Y-995000D02*
Y-1070000D01*
G01X335000Y-995000D02*
Y-1070000D01*
G01X342507Y-1055000D02*
Y-1050000D01*
X343773D01*
X344280Y-1050250D01*
X344660Y-1050583D01*
X344977Y-1051083D01*
X345230Y-1051667D01*
X345293Y-1052500D01*
X345230Y-1053333D01*
X344977Y-1053917D01*
X344660Y-1054417D01*
X344280Y-1054750D01*
X343773Y-1055000D01*
X342507D01*
G01X347417D02*
X349000Y-1050000D01*
X350583Y-1055000D01*
G01X350013Y-1053250D02*
X347987D01*
G01X354100Y-1050000D02*
Y-1055000D01*
G01X352643Y-1050000D02*
X355557D01*
G01X360467Y-1055000D02*
X357933D01*
Y-1050000D01*
X360467D01*
G01X359453Y-1052417D02*
X357933D01*
G01X364300Y-1055167D02*
X364173Y-1055083D01*
Y-1054917D01*
X364300Y-1054833D01*
X364427Y-1054917D01*
Y-1055083D01*
X364300Y-1055167D01*
G01Y-1052917D02*
X364173Y-1052833D01*
Y-1052667D01*
X364300Y-1052583D01*
X364427Y-1052667D01*
Y-1052833D01*
X364300Y-1052917D01*
G01X337000Y-1045000D02*
X537000D01*
G01X342633Y-1030000D02*
Y-1025000D01*
X344153D01*
X344660Y-1025250D01*
X345040Y-1025833D01*
X345167Y-1026500D01*
X345040Y-1027167D01*
X344723Y-1027667D01*
X344153Y-1027917D01*
X342633D01*
G01X347860Y-1030167D02*
X350140Y-1025000D01*
G01X352643Y-1030000D02*
Y-1025000D01*
X355557Y-1030000D01*
Y-1025000D01*
G01X359200Y-1030167D02*
X359073Y-1030083D01*
Y-1029917D01*
X359200Y-1029833D01*
X359327Y-1029917D01*
Y-1030083D01*
X359200Y-1030167D01*
G01Y-1027917D02*
X359073Y-1027833D01*
Y-1027667D01*
X359200Y-1027583D01*
X359327Y-1027667D01*
Y-1027833D01*
X359200Y-1027917D01*
G01X342633Y-1005000D02*
Y-1000000D01*
X344153D01*
X344660Y-1000250D01*
X345040Y-1000833D01*
X345167Y-1001500D01*
X345040Y-1002167D01*
X344723Y-1002667D01*
X344153Y-1002917D01*
X342633D01*
G01X347733Y-1005000D02*
Y-1000000D01*
X349317D01*
X349823Y-1000250D01*
X350140Y-1000583D01*
X350267Y-1001250D01*
X350140Y-1001917D01*
X349760Y-1002333D01*
X349317Y-1002583D01*
X347733D01*
G01X349317D02*
X350267Y-1005000D01*
G01X354100D02*
X353593Y-1004917D01*
X353150Y-1004583D01*
X352770Y-1004083D01*
X352517Y-1003500D01*
X352390Y-1002833D01*
Y-1002167D01*
X352517Y-1001500D01*
X352770Y-1000917D01*
X353150Y-1000417D01*
X353593Y-1000083D01*
X354100Y-1000000D01*
X354607Y-1000083D01*
X355050Y-1000417D01*
X355430Y-1000917D01*
X355683Y-1001500D01*
X355810Y-1002167D01*
Y-1002833D01*
X355683Y-1003500D01*
X355430Y-1004083D01*
X355050Y-1004583D01*
X354607Y-1004917D01*
X354100Y-1005000D01*
G01X357933Y-1004000D02*
X358250Y-1004500D01*
X358630Y-1004833D01*
X359073Y-1005000D01*
X359580Y-1004833D01*
X359960Y-1004500D01*
X360340Y-1004000D01*
X360467Y-1003333D01*
Y-1000000D01*
G01X365567Y-1005000D02*
X363033D01*
Y-1000000D01*
X365567D01*
G01X364553Y-1002417D02*
X363033D01*
G01X370793Y-1000417D02*
X370413Y-1000167D01*
X369970Y-1000000D01*
X369463D01*
X368893Y-1000250D01*
X368450Y-1000667D01*
X368133Y-1001167D01*
X367880Y-1002000D01*
X367817Y-1002750D01*
X367943Y-1003500D01*
X368133Y-1004000D01*
X368513Y-1004500D01*
X368957Y-1004833D01*
X369400Y-1005000D01*
X369843D01*
X370287Y-1004833D01*
X370667Y-1004583D01*
X370983Y-1004250D01*
G01X374500Y-1000000D02*
Y-1005000D01*
G01X373043Y-1000000D02*
X375957D01*
G01X379600Y-1005167D02*
X379473Y-1005083D01*
Y-1004917D01*
X379600Y-1004833D01*
X379727Y-1004917D01*
Y-1005083D01*
X379600Y-1005167D01*
G01Y-1002917D02*
X379473Y-1002833D01*
Y-1002667D01*
X379600Y-1002583D01*
X379727Y-1002667D01*
Y-1002833D01*
X379600Y-1002917D01*
G01X337000Y-1020000D02*
X537000D01*
G01X452000Y-1045000D02*
Y-1070000D01*
G01X454633Y-1047500D02*
Y-1052500D01*
X457167D01*
G01X460240Y-1047500D02*
X461760D01*
G01X461000D02*
Y-1052500D01*
G01X460240D02*
X461760D01*
G01X466607Y-1049833D02*
X466860Y-1049583D01*
X467050Y-1049167D01*
X467177Y-1048583D01*
X467050Y-1048083D01*
X466797Y-1047750D01*
X466353Y-1047500D01*
X464643D01*
Y-1052500D01*
X466733D01*
X467177Y-1052167D01*
X467430Y-1051667D01*
X467557Y-1051083D01*
X467430Y-1050500D01*
X467050Y-1050000D01*
X466607Y-1049833D01*
X464643D01*
G01X471200Y-1052667D02*
X471073Y-1052583D01*
Y-1052417D01*
X471200Y-1052333D01*
X471327Y-1052417D01*
Y-1052583D01*
X471200Y-1052667D01*
G01Y-1050417D02*
X471073Y-1050333D01*
Y-1050167D01*
X471200Y-1050083D01*
X471327Y-1050167D01*
Y-1050333D01*
X471200Y-1050417D01*
G01X495000Y-1045000D02*
Y-1070000D01*
G01X498900Y-1047500D02*
Y-1052500D01*
G01X497443Y-1047500D02*
X500357D01*
G01X504000Y-1052500D02*
X503620Y-1052417D01*
X503240Y-1052083D01*
X502987Y-1051500D01*
X502860Y-1050833D01*
X502987Y-1050167D01*
X503240Y-1049583D01*
X503620Y-1049250D01*
X504000Y-1049167D01*
X504380Y-1049250D01*
X504760Y-1049583D01*
X505013Y-1050167D01*
X505077Y-1050833D01*
X505013Y-1051500D01*
X504760Y-1052083D01*
X504380Y-1052417D01*
X504000Y-1052500D01*
G01X509100D02*
X508720Y-1052417D01*
X508340Y-1052083D01*
X508087Y-1051500D01*
X507960Y-1050833D01*
X508087Y-1050167D01*
X508340Y-1049583D01*
X508720Y-1049250D01*
X509100Y-1049167D01*
X509480Y-1049250D01*
X509860Y-1049583D01*
X510113Y-1050167D01*
X510177Y-1050833D01*
X510113Y-1051500D01*
X509860Y-1052083D01*
X509480Y-1052417D01*
X509100Y-1052500D01*
G01X514200D02*
Y-1047500D01*
G01X519300Y-1052667D02*
X519173Y-1052583D01*
Y-1052417D01*
X519300Y-1052333D01*
X519427Y-1052417D01*
Y-1052583D01*
X519300Y-1052667D01*
G01Y-1050417D02*
X519173Y-1050333D01*
Y-1050167D01*
X519300Y-1050083D01*
X519427Y-1050167D01*
Y-1050333D01*
X519300Y-1050417D01*
G01X495000Y-1020000D02*
Y-1045000D01*
G01X497633Y-1027500D02*
Y-1022500D01*
X499217D01*
X499723Y-1022750D01*
X500040Y-1023083D01*
X500167Y-1023750D01*
X500040Y-1024417D01*
X499660Y-1024833D01*
X499217Y-1025083D01*
X497633D01*
G01X499217D02*
X500167Y-1027500D01*
G01X505267D02*
X502733D01*
Y-1022500D01*
X505267D01*
G01X504253Y-1024917D02*
X502733D01*
G01X507517Y-1022500D02*
X509100Y-1027500D01*
X510683Y-1022500D01*
G01X514200Y-1027667D02*
X514073Y-1027583D01*
Y-1027417D01*
X514200Y-1027333D01*
X514327Y-1027417D01*
Y-1027583D01*
X514200Y-1027667D01*
G01Y-1025417D02*
X514073Y-1025333D01*
Y-1025167D01*
X514200Y-1025083D01*
X514327Y-1025167D01*
Y-1025333D01*
X514200Y-1025417D01*
G01X503013Y-1073167D02*
X503120Y-1073042D01*
X503200Y-1072833D01*
X503253Y-1072542D01*
X503200Y-1072292D01*
X503093Y-1072125D01*
X502907Y-1072000D01*
X502187D01*
Y-1074500D01*
X503067D01*
X503253Y-1074333D01*
X503360Y-1074083D01*
X503413Y-1073792D01*
X503360Y-1073500D01*
X503200Y-1073250D01*
X503013Y-1073167D01*
X502187D01*
G01X505480Y-1074500D02*
Y-1072833D01*
G01Y-1073125D02*
X505373Y-1072958D01*
X505213Y-1072875D01*
X505027Y-1072833D01*
X504840Y-1072917D01*
X504680Y-1073083D01*
X504573Y-1073333D01*
X504520Y-1073667D01*
X504573Y-1074000D01*
X504680Y-1074250D01*
X504840Y-1074417D01*
X505027Y-1074500D01*
X505213Y-1074458D01*
X505373Y-1074333D01*
X505480Y-1074167D01*
G01X506800Y-1074208D02*
X506933Y-1074375D01*
X507120Y-1074500D01*
X507280D01*
X507440Y-1074417D01*
X507547Y-1074292D01*
X507600Y-1074125D01*
X507573Y-1073875D01*
X507467Y-1073750D01*
X506987Y-1073500D01*
X506880Y-1073208D01*
X506933Y-1073000D01*
X507040Y-1072875D01*
X507200Y-1072833D01*
X507360Y-1072875D01*
X507520Y-1073000D01*
G01X509000Y-1073375D02*
X509853D01*
X509773Y-1073083D01*
X509640Y-1072917D01*
X509453Y-1072833D01*
X509267Y-1072875D01*
X509107Y-1073000D01*
X509000Y-1073292D01*
X508947Y-1073542D01*
Y-1073792D01*
X509000Y-1074042D01*
X509133Y-1074292D01*
X509293Y-1074458D01*
X509480Y-1074500D01*
X509667Y-1074417D01*
X509853Y-1074167D01*
G01X511120Y-1074500D02*
Y-1072000D01*
G01Y-1073250D02*
X511253Y-1073000D01*
X511413Y-1072875D01*
X511573Y-1072833D01*
X511813Y-1072917D01*
X511973Y-1073083D01*
X512080Y-1073375D01*
Y-1073708D01*
X512027Y-1074042D01*
X511920Y-1074292D01*
X511733Y-1074458D01*
X511573Y-1074500D01*
X511413Y-1074458D01*
X511253Y-1074333D01*
X511120Y-1074125D01*
G01X513800Y-1074500D02*
X513640Y-1074458D01*
X513480Y-1074292D01*
X513373Y-1074000D01*
X513320Y-1073667D01*
X513373Y-1073333D01*
X513480Y-1073042D01*
X513640Y-1072875D01*
X513800Y-1072833D01*
X513960Y-1072875D01*
X514120Y-1073042D01*
X514227Y-1073333D01*
X514253Y-1073667D01*
X514227Y-1074000D01*
X514120Y-1074292D01*
X513960Y-1074458D01*
X513800Y-1074500D01*
G01X516480D02*
Y-1072833D01*
G01Y-1073125D02*
X516373Y-1072958D01*
X516213Y-1072875D01*
X516027Y-1072833D01*
X515840Y-1072917D01*
X515680Y-1073083D01*
X515573Y-1073333D01*
X515520Y-1073667D01*
X515573Y-1074000D01*
X515680Y-1074250D01*
X515840Y-1074417D01*
X516027Y-1074500D01*
X516213Y-1074458D01*
X516373Y-1074333D01*
X516480Y-1074167D01*
G01X517827Y-1074500D02*
Y-1072833D01*
G01Y-1073167D02*
X517960Y-1073000D01*
X518093Y-1072875D01*
X518280Y-1072833D01*
X518413Y-1072875D01*
X518573Y-1073000D01*
G01X520880Y-1072000D02*
Y-1074500D01*
G01Y-1074125D02*
X520773Y-1074333D01*
X520613Y-1074458D01*
X520427Y-1074500D01*
X520213Y-1074417D01*
X520053Y-1074208D01*
X519947Y-1073958D01*
X519920Y-1073667D01*
X519947Y-1073375D01*
X520053Y-1073125D01*
X520213Y-1072917D01*
X520427Y-1072833D01*
X520613Y-1072875D01*
X520747Y-1072958D01*
X520880Y-1073125D01*
G01X524267Y-1074500D02*
Y-1072000D01*
X524933D01*
X525147Y-1072125D01*
X525280Y-1072292D01*
X525333Y-1072625D01*
X525280Y-1072958D01*
X525120Y-1073167D01*
X524933Y-1073292D01*
X524267D01*
G01X524933D02*
X525333Y-1074500D01*
G01X526600Y-1073375D02*
X527453D01*
X527373Y-1073083D01*
X527240Y-1072917D01*
X527053Y-1072833D01*
X526867Y-1072875D01*
X526707Y-1073000D01*
X526600Y-1073292D01*
X526547Y-1073542D01*
Y-1073792D01*
X526600Y-1074042D01*
X526733Y-1074292D01*
X526893Y-1074458D01*
X527080Y-1074500D01*
X527267Y-1074417D01*
X527453Y-1074167D01*
G01X528720Y-1072833D02*
X529200Y-1074500D01*
X529680Y-1072833D01*
G01X531400Y-1074583D02*
X531347Y-1074542D01*
Y-1074458D01*
X531400Y-1074417D01*
X531453Y-1074458D01*
Y-1074542D01*
X531400Y-1074583D01*
G01X533600Y-1074500D02*
X533787Y-1074458D01*
X534000Y-1074333D01*
X534133Y-1074125D01*
X534187Y-1073833D01*
X534133Y-1073542D01*
X533973Y-1073292D01*
X533733Y-1073167D01*
X533467D01*
X533307Y-1073083D01*
X533173Y-1072875D01*
X533120Y-1072583D01*
X533200Y-1072292D01*
X533387Y-1072083D01*
X533600Y-1072000D01*
X533813Y-1072083D01*
X534000Y-1072292D01*
X534080Y-1072583D01*
X534027Y-1072875D01*
X533893Y-1073083D01*
X533733Y-1073167D01*
X533467D01*
X533227Y-1073292D01*
X533067Y-1073542D01*
X533013Y-1073833D01*
X533067Y-1074125D01*
X533200Y-1074333D01*
X533413Y-1074458D01*
X533600Y-1074500D01*
G01X536013Y-1073167D02*
X536120Y-1073042D01*
X536200Y-1072833D01*
X536253Y-1072542D01*
X536200Y-1072292D01*
X536093Y-1072125D01*
X535907Y-1072000D01*
X535187D01*
Y-1074500D01*
X536067D01*
X536253Y-1074333D01*
X536360Y-1074083D01*
X536413Y-1073792D01*
X536360Y-1073500D01*
X536200Y-1073250D01*
X536013Y-1073167D01*
X535187D01*
G01X-457143Y-1211429D02*
Y2242857D01*
X4308572D01*
Y-1211429D01*
X-457143D01*
G01X71650Y-1024800D02*
X69130Y-1024383D01*
X66925Y-1022717D01*
X65035Y-1020217D01*
X63775Y-1017300D01*
X63145Y-1013967D01*
Y-1010633D01*
X63775Y-1007300D01*
X65035Y-1004383D01*
X66925Y-1001884D01*
X69130Y-1000217D01*
X71650Y-999800D01*
X74170Y-1000217D01*
X76375Y-1001884D01*
X78265Y-1004383D01*
X79525Y-1007300D01*
X80155Y-1010633D01*
Y-1013967D01*
X79525Y-1017300D01*
X78265Y-1020217D01*
X76375Y-1022717D01*
X74170Y-1024383D01*
X71650Y-1024800D01*
G01X74170Y-1018133D02*
X77950Y-1024800D01*
G01X91495Y-1008134D02*
Y-1019800D01*
X92755Y-1022717D01*
X94645Y-1024383D01*
X96850Y-1024800D01*
X99055Y-1024383D01*
X100945Y-1022717D01*
X102205Y-1019800D01*
G01Y-1024800D02*
Y-1008134D01*
G01X127720Y-1024800D02*
Y-1008134D01*
G01Y-1011050D02*
X126460Y-1009384D01*
X124570Y-1008550D01*
X122365Y-1008134D01*
X120160Y-1008967D01*
X118270Y-1010633D01*
X117010Y-1013134D01*
X116380Y-1016467D01*
X117010Y-1019800D01*
X118270Y-1022301D01*
X120160Y-1023967D01*
X122365Y-1024800D01*
X124570Y-1024383D01*
X126460Y-1023134D01*
X127720Y-1021467D01*
G01X141895Y-1024800D02*
Y-1008134D01*
G01Y-1012300D02*
X143155Y-1010217D01*
X145045Y-1008550D01*
X147565Y-1008134D01*
X149770Y-1008550D01*
X151660Y-1010217D01*
X152605Y-1013134D01*
Y-1024800D01*
G01X172450Y-999800D02*
Y-1024800D01*
G01X168040Y-1008134D02*
X176860D01*
G01X203320Y-1024800D02*
Y-1008134D01*
G01Y-1011050D02*
X202060Y-1009384D01*
X200170Y-1008550D01*
X197965Y-1008134D01*
X195760Y-1008967D01*
X193870Y-1010633D01*
X192610Y-1013134D01*
X191980Y-1016467D01*
X192610Y-1019800D01*
X193870Y-1022301D01*
X195760Y-1023967D01*
X197965Y-1024800D01*
X200170Y-1024383D01*
X202060Y-1023134D01*
X203320Y-1021467D01*
G01X49820Y-1042350D02*
X51387D01*
Y-1044240D01*
X50917Y-1044870D01*
X50368Y-1045290D01*
X49585Y-1045500D01*
X48802Y-1045290D01*
X48253Y-1044870D01*
X47783Y-1044240D01*
X47470Y-1043505D01*
X47313Y-1042665D01*
Y-1041930D01*
X47470Y-1041300D01*
X47783Y-1040565D01*
X48253Y-1039935D01*
X48723Y-1039515D01*
X49350Y-1039200D01*
X49898D01*
X50525Y-1039410D01*
X50995Y-1039830D01*
G01X53927Y-1039200D02*
Y-1043715D01*
X54240Y-1044660D01*
X54867Y-1045290D01*
X55650Y-1045500D01*
X56433Y-1045290D01*
X57060Y-1044660D01*
X57373Y-1043715D01*
Y-1039200D01*
G01X61010D02*
X62890D01*
G01X61950D02*
Y-1045500D01*
G01X61010D02*
X62890D01*
G01X66605Y-1044660D02*
X67232Y-1045185D01*
X67937Y-1045500D01*
X68563D01*
X69190Y-1045185D01*
X69660Y-1044660D01*
X69895Y-1043925D01*
X69738Y-1043190D01*
X69347Y-1042560D01*
X68642Y-1042140D01*
X67702Y-1041930D01*
X67153Y-1041510D01*
X66918Y-1040775D01*
X67075Y-1040040D01*
X67467Y-1039515D01*
X68015Y-1039200D01*
X68563D01*
X69112Y-1039410D01*
X69582Y-1039935D01*
G01X72905Y-1045500D02*
Y-1039200D01*
G01X76195D02*
Y-1045500D01*
G01Y-1042350D02*
X72905D01*
G01X78892Y-1045500D02*
X80850Y-1039200D01*
X82808Y-1045500D01*
G01X82103Y-1043295D02*
X79597D01*
G01X85348Y-1045500D02*
Y-1039200D01*
X88952Y-1045500D01*
Y-1039200D01*
G01X98027Y-1045500D02*
Y-1039200D01*
X99593D01*
X100220Y-1039515D01*
X100690Y-1039935D01*
X101082Y-1040565D01*
X101395Y-1041300D01*
X101473Y-1042350D01*
X101395Y-1043400D01*
X101082Y-1044135D01*
X100690Y-1044765D01*
X100220Y-1045185D01*
X99593Y-1045500D01*
X98027D01*
G01X105110Y-1039200D02*
X106990D01*
G01X106050D02*
Y-1045500D01*
G01X105110D02*
X106990D01*
G01X110705Y-1044660D02*
X111332Y-1045185D01*
X112037Y-1045500D01*
X112663D01*
X113290Y-1045185D01*
X113760Y-1044660D01*
X113995Y-1043925D01*
X113838Y-1043190D01*
X113447Y-1042560D01*
X112742Y-1042140D01*
X111802Y-1041930D01*
X111253Y-1041510D01*
X111018Y-1040775D01*
X111175Y-1040040D01*
X111567Y-1039515D01*
X112115Y-1039200D01*
X112663D01*
X113212Y-1039410D01*
X113682Y-1039935D01*
G01X118650Y-1039200D02*
Y-1045500D01*
G01X116848Y-1039200D02*
X120452D01*
G01X124950Y-1045710D02*
X124793Y-1045605D01*
Y-1045395D01*
X124950Y-1045290D01*
X125107Y-1045395D01*
Y-1045605D01*
X124950Y-1045710D01*
G01X131093Y-1046655D02*
X131407Y-1045290D01*
G01X137550Y-1039200D02*
Y-1045500D01*
G01X135748Y-1039200D02*
X139352D01*
G01X141892Y-1045500D02*
X143850Y-1039200D01*
X145808Y-1045500D01*
G01X145103Y-1043295D02*
X142597D01*
G01X150150Y-1045500D02*
X149523Y-1045395D01*
X148975Y-1044975D01*
X148505Y-1044345D01*
X148192Y-1043610D01*
X148035Y-1042770D01*
Y-1041930D01*
X148192Y-1041090D01*
X148505Y-1040355D01*
X148975Y-1039725D01*
X149523Y-1039305D01*
X150150Y-1039200D01*
X150777Y-1039305D01*
X151325Y-1039725D01*
X151795Y-1040355D01*
X152108Y-1041090D01*
X152265Y-1041930D01*
Y-1042770D01*
X152108Y-1043610D01*
X151795Y-1044345D01*
X151325Y-1044975D01*
X150777Y-1045395D01*
X150150Y-1045500D01*
G01X156450D02*
Y-1042665D01*
X154883Y-1039200D01*
G01X158017D02*
X156450Y-1042665D01*
G01X161027Y-1039200D02*
Y-1043715D01*
X161340Y-1044660D01*
X161967Y-1045290D01*
X162750Y-1045500D01*
X163533Y-1045290D01*
X164160Y-1044660D01*
X164473Y-1043715D01*
Y-1039200D01*
G01X167092Y-1045500D02*
X169050Y-1039200D01*
X171008Y-1045500D01*
G01X170303Y-1043295D02*
X167797D01*
G01X173548Y-1045500D02*
Y-1039200D01*
X177152Y-1045500D01*
Y-1039200D01*
G01X51073Y-1049725D02*
X50603Y-1049410D01*
X50055Y-1049200D01*
X49428D01*
X48723Y-1049515D01*
X48175Y-1050040D01*
X47783Y-1050670D01*
X47470Y-1051720D01*
X47392Y-1052665D01*
X47548Y-1053610D01*
X47783Y-1054240D01*
X48253Y-1054870D01*
X48802Y-1055290D01*
X49350Y-1055500D01*
X49898D01*
X50447Y-1055290D01*
X50917Y-1054975D01*
X51308Y-1054555D01*
G01X54710Y-1049200D02*
X56590D01*
G01X55650D02*
Y-1055500D01*
G01X54710D02*
X56590D01*
G01X61950Y-1049200D02*
Y-1055500D01*
G01X60148Y-1049200D02*
X63752D01*
G01X68250Y-1055500D02*
Y-1052665D01*
X66683Y-1049200D01*
G01X69817D02*
X68250Y-1052665D01*
G01X79127Y-1054240D02*
X79597Y-1054975D01*
X80223Y-1055395D01*
X80928Y-1055500D01*
X81555Y-1055395D01*
X82182Y-1054870D01*
X82573Y-1054240D01*
X82652Y-1053610D01*
X82495Y-1052875D01*
X81947Y-1052350D01*
X81398Y-1052140D01*
X80693D01*
G01X81398D02*
X81868Y-1051825D01*
X82260Y-1051300D01*
X82417Y-1050670D01*
X82260Y-1050040D01*
X81868Y-1049515D01*
X81163Y-1049200D01*
X80458Y-1049305D01*
X79753Y-1049725D01*
G01X85427Y-1054240D02*
X85897Y-1054975D01*
X86523Y-1055395D01*
X87228Y-1055500D01*
X87855Y-1055395D01*
X88482Y-1054870D01*
X88873Y-1054240D01*
X88952Y-1053610D01*
X88795Y-1052875D01*
X88247Y-1052350D01*
X87698Y-1052140D01*
X86993D01*
G01X87698D02*
X88168Y-1051825D01*
X88560Y-1051300D01*
X88717Y-1050670D01*
X88560Y-1050040D01*
X88168Y-1049515D01*
X87463Y-1049200D01*
X86758Y-1049305D01*
X86053Y-1049725D01*
G01X91727Y-1054240D02*
X92197Y-1054975D01*
X92823Y-1055395D01*
X93528Y-1055500D01*
X94155Y-1055395D01*
X94782Y-1054870D01*
X95173Y-1054240D01*
X95252Y-1053610D01*
X95095Y-1052875D01*
X94547Y-1052350D01*
X93998Y-1052140D01*
X93293D01*
G01X93998D02*
X94468Y-1051825D01*
X94860Y-1051300D01*
X95017Y-1050670D01*
X94860Y-1050040D01*
X94468Y-1049515D01*
X93763Y-1049200D01*
X93058Y-1049305D01*
X92353Y-1049725D01*
G01X99593Y-1055500D02*
X99750Y-1054135D01*
X99985Y-1052980D01*
X100298Y-1051930D01*
X100690Y-1050775D01*
X101317Y-1049200D01*
X98183D01*
G01X105893Y-1055500D02*
X106050Y-1054135D01*
X106285Y-1052980D01*
X106598Y-1051930D01*
X106990Y-1050775D01*
X107617Y-1049200D01*
X104483D01*
G01X112193Y-1056655D02*
X112507Y-1055290D01*
G01X118650Y-1049200D02*
Y-1055500D01*
G01X116848Y-1049200D02*
X120452D01*
G01X122992Y-1055500D02*
X124950Y-1049200D01*
X126908Y-1055500D01*
G01X126203Y-1053295D02*
X123697D01*
G01X130310Y-1049200D02*
X132190D01*
G01X131250D02*
Y-1055500D01*
G01X130310D02*
X132190D01*
G01X135200Y-1049200D02*
X136297Y-1055500D01*
X137550Y-1049200D01*
X138803Y-1055500D01*
X139900Y-1049200D01*
G01X141892Y-1055500D02*
X143850Y-1049200D01*
X145808Y-1055500D01*
G01X145103Y-1053295D02*
X142597D01*
G01X148348Y-1055500D02*
Y-1049200D01*
X151952Y-1055500D01*
Y-1049200D01*
G01X162358Y-1057600D02*
X161575Y-1056550D01*
X161183Y-1055500D01*
Y-1051300D01*
X161575Y-1050250D01*
X162358Y-1049200D01*
G01X173783Y-1055500D02*
Y-1049200D01*
X175742D01*
X176368Y-1049515D01*
X176760Y-1049935D01*
X176917Y-1050775D01*
X176760Y-1051615D01*
X176290Y-1052140D01*
X175742Y-1052455D01*
X173783D01*
G01X175742D02*
X176917Y-1055500D01*
G01X181650Y-1055710D02*
X181493Y-1055605D01*
Y-1055395D01*
X181650Y-1055290D01*
X181807Y-1055395D01*
Y-1055605D01*
X181650Y-1055710D01*
G01X187950Y-1055500D02*
X187323Y-1055395D01*
X186775Y-1054975D01*
X186305Y-1054345D01*
X185992Y-1053610D01*
X185835Y-1052770D01*
Y-1051930D01*
X185992Y-1051090D01*
X186305Y-1050355D01*
X186775Y-1049725D01*
X187323Y-1049305D01*
X187950Y-1049200D01*
X188577Y-1049305D01*
X189125Y-1049725D01*
X189595Y-1050355D01*
X189908Y-1051090D01*
X190065Y-1051930D01*
Y-1052770D01*
X189908Y-1053610D01*
X189595Y-1054345D01*
X189125Y-1054975D01*
X188577Y-1055395D01*
X187950Y-1055500D01*
G01X194250Y-1055710D02*
X194093Y-1055605D01*
Y-1055395D01*
X194250Y-1055290D01*
X194407Y-1055395D01*
Y-1055605D01*
X194250Y-1055710D01*
G01X202273Y-1049725D02*
X201803Y-1049410D01*
X201255Y-1049200D01*
X200628D01*
X199923Y-1049515D01*
X199375Y-1050040D01*
X198983Y-1050670D01*
X198670Y-1051720D01*
X198592Y-1052665D01*
X198748Y-1053610D01*
X198983Y-1054240D01*
X199453Y-1054870D01*
X200002Y-1055290D01*
X200550Y-1055500D01*
X201098D01*
X201647Y-1055290D01*
X202117Y-1054975D01*
X202508Y-1054555D01*
G01X206850Y-1055710D02*
X206693Y-1055605D01*
Y-1055395D01*
X206850Y-1055290D01*
X207007Y-1055395D01*
Y-1055605D01*
X206850Y-1055710D01*
G01X213542Y-1057600D02*
X214325Y-1056550D01*
X214717Y-1055500D01*
Y-1051300D01*
X214325Y-1050250D01*
X213542Y-1049200D01*
G01X47548Y-1035500D02*
Y-1029200D01*
X51152Y-1035500D01*
Y-1029200D01*
G01X55650Y-1035500D02*
X55023Y-1035395D01*
X54475Y-1034975D01*
X54005Y-1034345D01*
X53692Y-1033610D01*
X53535Y-1032770D01*
Y-1031930D01*
X53692Y-1031090D01*
X54005Y-1030355D01*
X54475Y-1029725D01*
X55023Y-1029305D01*
X55650Y-1029200D01*
X56277Y-1029305D01*
X56825Y-1029725D01*
X57295Y-1030355D01*
X57608Y-1031090D01*
X57765Y-1031930D01*
Y-1032770D01*
X57608Y-1033610D01*
X57295Y-1034345D01*
X56825Y-1034975D01*
X56277Y-1035395D01*
X55650Y-1035500D01*
G01X61950Y-1035710D02*
X61793Y-1035605D01*
Y-1035395D01*
X61950Y-1035290D01*
X62107Y-1035395D01*
Y-1035605D01*
X61950Y-1035710D01*
G01X66762Y-1030250D02*
X67232Y-1029620D01*
X67780Y-1029305D01*
X68407Y-1029200D01*
X69190Y-1029410D01*
X69738Y-1029935D01*
X69895Y-1030565D01*
X69817Y-1031195D01*
X69503Y-1031720D01*
X67937Y-1032770D01*
X67232Y-1033505D01*
X66762Y-1034555D01*
X66605Y-1035500D01*
X69895D01*
G01X74550D02*
Y-1029200D01*
X73610Y-1030460D01*
G01Y-1035500D02*
X75490D01*
G01X80850D02*
Y-1029200D01*
X79910Y-1030460D01*
G01Y-1035500D02*
X81790D01*
G01X86993Y-1036655D02*
X87307Y-1035290D01*
G01X91100Y-1029200D02*
X92197Y-1035500D01*
X93450Y-1029200D01*
X94703Y-1035500D01*
X95800Y-1029200D01*
G01X101317Y-1035500D02*
X98183D01*
Y-1029200D01*
X101317D01*
G01X100063Y-1032245D02*
X98183D01*
G01X104248Y-1035500D02*
Y-1029200D01*
X107852Y-1035500D01*
Y-1029200D01*
G01X110705Y-1035500D02*
Y-1029200D01*
G01X113995D02*
Y-1035500D01*
G01Y-1032350D02*
X110705D01*
G01X116927Y-1029200D02*
Y-1033715D01*
X117240Y-1034660D01*
X117867Y-1035290D01*
X118650Y-1035500D01*
X119433Y-1035290D01*
X120060Y-1034660D01*
X120373Y-1033715D01*
Y-1029200D01*
G01X122992Y-1035500D02*
X124950Y-1029200D01*
X126908Y-1035500D01*
G01X126203Y-1033295D02*
X123697D01*
G01X136062Y-1030250D02*
X136532Y-1029620D01*
X137080Y-1029305D01*
X137707Y-1029200D01*
X138490Y-1029410D01*
X139038Y-1029935D01*
X139195Y-1030565D01*
X139117Y-1031195D01*
X138803Y-1031720D01*
X137237Y-1032770D01*
X136532Y-1033505D01*
X136062Y-1034555D01*
X135905Y-1035500D01*
X139195D01*
G01X142048D02*
Y-1029200D01*
X145652Y-1035500D01*
Y-1029200D01*
G01X148427Y-1035500D02*
Y-1029200D01*
X149993D01*
X150620Y-1029515D01*
X151090Y-1029935D01*
X151482Y-1030565D01*
X151795Y-1031300D01*
X151873Y-1032350D01*
X151795Y-1033400D01*
X151482Y-1034135D01*
X151090Y-1034765D01*
X150620Y-1035185D01*
X149993Y-1035500D01*
X148427D01*
G01X161183D02*
Y-1029200D01*
X163142D01*
X163768Y-1029515D01*
X164160Y-1029935D01*
X164317Y-1030775D01*
X164160Y-1031615D01*
X163690Y-1032140D01*
X163142Y-1032455D01*
X161183D01*
G01X163142D02*
X164317Y-1035500D01*
G01X167327D02*
Y-1029200D01*
X168893D01*
X169520Y-1029515D01*
X169990Y-1029935D01*
X170382Y-1030565D01*
X170695Y-1031300D01*
X170773Y-1032350D01*
X170695Y-1033400D01*
X170382Y-1034135D01*
X169990Y-1034765D01*
X169520Y-1035185D01*
X168893Y-1035500D01*
X167327D01*
G01X175350Y-1035710D02*
X175193Y-1035605D01*
Y-1035395D01*
X175350Y-1035290D01*
X175507Y-1035395D01*
Y-1035605D01*
X175350Y-1035710D01*
G01X243000Y-1004500D02*
Y-1012500D01*
X247000D01*
G01X254800D02*
Y-1007167D01*
G01Y-1008100D02*
X254400Y-1007567D01*
X253800Y-1007300D01*
X253100Y-1007167D01*
X252400Y-1007433D01*
X251800Y-1007967D01*
X251400Y-1008767D01*
X251200Y-1009833D01*
X251400Y-1010900D01*
X251800Y-1011700D01*
X252400Y-1012233D01*
X253100Y-1012500D01*
X253800Y-1012367D01*
X254400Y-1011967D01*
X254800Y-1011434D01*
G01X258900Y-1014900D02*
X259500Y-1015167D01*
X260300Y-1014900D01*
X260800Y-1014367D01*
X261200Y-1013700D01*
X261800Y-1011567D01*
X263100Y-1007167D01*
G01X259900D02*
X261800Y-1011567D01*
G01X267500Y-1008900D02*
X270700D01*
X270400Y-1007967D01*
X269900Y-1007433D01*
X269200Y-1007167D01*
X268500Y-1007300D01*
X267900Y-1007700D01*
X267500Y-1008633D01*
X267300Y-1009434D01*
Y-1010233D01*
X267500Y-1011033D01*
X268000Y-1011833D01*
X268600Y-1012367D01*
X269300Y-1012500D01*
X270000Y-1012233D01*
X270700Y-1011434D01*
G01X275600Y-1012500D02*
Y-1007167D01*
G01Y-1008233D02*
X276100Y-1007700D01*
X276600Y-1007300D01*
X277300Y-1007167D01*
X277800Y-1007300D01*
X278400Y-1007700D01*
G01X262100Y-1054500D02*
X265900D01*
X262100Y-1062500D01*
X265900D01*
G01X272000Y-1057167D02*
Y-1062500D01*
G01Y-1055033D02*
X271800Y-1054900D01*
Y-1054633D01*
X272000Y-1054500D01*
X272200Y-1054633D01*
Y-1054900D01*
X272000Y-1055033D01*
G01X278700Y-1059833D02*
X281300D01*
G01X286200Y-1065167D02*
Y-1057167D01*
G01Y-1058367D02*
X286700Y-1057700D01*
X287200Y-1057300D01*
X288000Y-1057167D01*
X288700Y-1057300D01*
X289400Y-1057967D01*
X289700Y-1058900D01*
X289800Y-1059833D01*
X289700Y-1060767D01*
X289400Y-1061700D01*
X288800Y-1062233D01*
X288000Y-1062500D01*
X287300Y-1062367D01*
X286600Y-1061967D01*
X286200Y-1061434D01*
G01X296000Y-1057167D02*
Y-1062500D01*
G01Y-1055033D02*
X295800Y-1054900D01*
Y-1054633D01*
X296000Y-1054500D01*
X296200Y-1054633D01*
Y-1054900D01*
X296000Y-1055033D01*
G01X302300Y-1062500D02*
Y-1057167D01*
G01Y-1058500D02*
X302700Y-1057833D01*
X303300Y-1057300D01*
X304100Y-1057167D01*
X304800Y-1057300D01*
X305400Y-1057833D01*
X305700Y-1058767D01*
Y-1062500D01*
G01X310600Y-1064500D02*
X311300Y-1065033D01*
X312100Y-1065167D01*
X312800Y-1065033D01*
X313400Y-1064367D01*
X313800Y-1063433D01*
Y-1057167D01*
G01Y-1058233D02*
X313400Y-1057700D01*
X312800Y-1057300D01*
X312100Y-1057167D01*
X311300Y-1057433D01*
X310800Y-1057967D01*
X310400Y-1058900D01*
X310200Y-1059833D01*
X310300Y-1060633D01*
X310700Y-1061567D01*
X311300Y-1062233D01*
X312100Y-1062500D01*
X312700Y-1062367D01*
X313400Y-1061833D01*
X313800Y-1061300D01*
G01X274600Y-1033500D02*
X276600D01*
Y-1035900D01*
X276000Y-1036700D01*
X275300Y-1037233D01*
X274300Y-1037500D01*
X273300Y-1037233D01*
X272600Y-1036700D01*
X272000Y-1035900D01*
X271600Y-1034967D01*
X271400Y-1033900D01*
Y-1032967D01*
X271600Y-1032167D01*
X272000Y-1031233D01*
X272600Y-1030433D01*
X273200Y-1029900D01*
X274000Y-1029500D01*
X274700D01*
X275500Y-1029767D01*
X276100Y-1030300D01*
G01X279700Y-1037500D02*
Y-1029500D01*
X284300Y-1037500D01*
Y-1029500D01*
G01X287800Y-1037500D02*
Y-1029500D01*
X289800D01*
X290600Y-1029900D01*
X291200Y-1030433D01*
X291700Y-1031233D01*
X292100Y-1032167D01*
X292200Y-1033500D01*
X292100Y-1034833D01*
X291700Y-1035767D01*
X291200Y-1036567D01*
X290600Y-1037100D01*
X289800Y-1037500D01*
X287800D01*
G01X295800Y-1035900D02*
X296400Y-1036833D01*
X297200Y-1037367D01*
X298100Y-1037500D01*
X298900Y-1037367D01*
X299700Y-1036700D01*
X300200Y-1035900D01*
X300300Y-1035100D01*
X300100Y-1034167D01*
X299400Y-1033500D01*
X298700Y-1033233D01*
X297800D01*
G01X298700D02*
X299300Y-1032833D01*
X299800Y-1032167D01*
X300000Y-1031367D01*
X299800Y-1030567D01*
X299300Y-1029900D01*
X298400Y-1029500D01*
X297500Y-1029633D01*
X296600Y-1030167D01*
G01X294800Y-1011567D02*
X295500Y-1012233D01*
X296300Y-1012500D01*
X297100Y-1012233D01*
X297800Y-1011434D01*
X298300Y-1010233D01*
X298500Y-1009033D01*
Y-1007567D01*
X298300Y-1006367D01*
X297800Y-1005300D01*
X297200Y-1004767D01*
X296500Y-1004500D01*
X295700Y-1004767D01*
X295100Y-1005300D01*
X294700Y-1006100D01*
X294500Y-1007167D01*
X294700Y-1008100D01*
X295200Y-1009033D01*
X295800Y-1009567D01*
X296500Y-1009700D01*
X297300Y-1009434D01*
X297900Y-1008767D01*
X298500Y-1007567D01*
G01X369600Y-1055833D02*
X370200Y-1055033D01*
X370900Y-1054633D01*
X371700Y-1054500D01*
X372700Y-1054767D01*
X373400Y-1055433D01*
X373600Y-1056233D01*
X373500Y-1057034D01*
X373100Y-1057700D01*
X371100Y-1059033D01*
X370200Y-1059967D01*
X369600Y-1061300D01*
X369400Y-1062500D01*
X373600D01*
G01X379500Y-1054500D02*
X378700Y-1054767D01*
X378100Y-1055433D01*
X377700Y-1056233D01*
X377400Y-1057300D01*
X377300Y-1058500D01*
X377400Y-1059700D01*
X377700Y-1060767D01*
X378100Y-1061567D01*
X378700Y-1062233D01*
X379500Y-1062500D01*
X380300Y-1062233D01*
X380900Y-1061567D01*
X381300Y-1060767D01*
X381600Y-1059700D01*
X381700Y-1058500D01*
X381600Y-1057300D01*
X381300Y-1056233D01*
X380900Y-1055433D01*
X380300Y-1054767D01*
X379500Y-1054500D01*
G01X385600Y-1055833D02*
X386200Y-1055033D01*
X386900Y-1054633D01*
X387700Y-1054500D01*
X388700Y-1054767D01*
X389400Y-1055433D01*
X389600Y-1056233D01*
X389500Y-1057034D01*
X389100Y-1057700D01*
X387100Y-1059033D01*
X386200Y-1059967D01*
X385600Y-1061300D01*
X385400Y-1062500D01*
X389600D01*
G01X393600Y-1055833D02*
X394200Y-1055033D01*
X394900Y-1054633D01*
X395700Y-1054500D01*
X396700Y-1054767D01*
X397400Y-1055433D01*
X397600Y-1056233D01*
X397500Y-1057034D01*
X397100Y-1057700D01*
X395100Y-1059033D01*
X394200Y-1059967D01*
X393600Y-1061300D01*
X393400Y-1062500D01*
X397600D01*
G01X401700Y-1062767D02*
X405300Y-1054500D01*
G01X411500Y-1062500D02*
Y-1054500D01*
X410300Y-1056100D01*
G01Y-1062500D02*
X412700D01*
G01X417600Y-1055833D02*
X418200Y-1055033D01*
X418900Y-1054633D01*
X419700Y-1054500D01*
X420700Y-1054767D01*
X421400Y-1055433D01*
X421600Y-1056233D01*
X421500Y-1057034D01*
X421100Y-1057700D01*
X419100Y-1059033D01*
X418200Y-1059967D01*
X417600Y-1061300D01*
X417400Y-1062500D01*
X421600D01*
G01X425700Y-1062767D02*
X429300Y-1054500D01*
G01X435500Y-1062500D02*
Y-1054500D01*
X434300Y-1056100D01*
G01Y-1062500D02*
X436700D01*
G01X441300Y-1060900D02*
X441900Y-1061833D01*
X442700Y-1062367D01*
X443600Y-1062500D01*
X444400Y-1062367D01*
X445200Y-1061700D01*
X445700Y-1060900D01*
X445800Y-1060100D01*
X445600Y-1059167D01*
X444900Y-1058500D01*
X444200Y-1058233D01*
X443300D01*
G01X444200D02*
X444800Y-1057833D01*
X445300Y-1057167D01*
X445500Y-1056367D01*
X445300Y-1055567D01*
X444800Y-1054900D01*
X443900Y-1054500D01*
X443000Y-1054633D01*
X442100Y-1055167D01*
G01X369300Y-1040000D02*
Y-1032000D01*
X371300D01*
X372100Y-1032400D01*
X372700Y-1032933D01*
X373200Y-1033733D01*
X373600Y-1034667D01*
X373700Y-1036000D01*
X373600Y-1037333D01*
X373200Y-1038267D01*
X372700Y-1039067D01*
X372100Y-1039600D01*
X371300Y-1040000D01*
X369300D01*
G01X377000D02*
X379500Y-1032000D01*
X382000Y-1040000D01*
G01X381100Y-1037200D02*
X377900D01*
G01X385600Y-1040000D02*
Y-1032000D01*
X389400D01*
G01X388000Y-1035867D02*
X385600D01*
G01X395500Y-1032000D02*
X394700Y-1032267D01*
X394100Y-1032933D01*
X393700Y-1033733D01*
X393400Y-1034800D01*
X393300Y-1036000D01*
X393400Y-1037200D01*
X393700Y-1038267D01*
X394100Y-1039067D01*
X394700Y-1039733D01*
X395500Y-1040000D01*
X396300Y-1039733D01*
X396900Y-1039067D01*
X397300Y-1038267D01*
X397600Y-1037200D01*
X397700Y-1036000D01*
X397600Y-1034800D01*
X397300Y-1033733D01*
X396900Y-1032933D01*
X396300Y-1032267D01*
X395500Y-1032000D01*
G01X403500D02*
Y-1040000D01*
G01X401200Y-1032000D02*
X405800D01*
G01X409500Y-1040000D02*
Y-1032000D01*
X411900D01*
X412700Y-1032400D01*
X413300Y-1033333D01*
X413500Y-1034400D01*
X413300Y-1035467D01*
X412800Y-1036267D01*
X411900Y-1036667D01*
X409500D01*
G01X420300Y-1035733D02*
X420700Y-1035333D01*
X421000Y-1034667D01*
X421200Y-1033733D01*
X421000Y-1032933D01*
X420600Y-1032400D01*
X419900Y-1032000D01*
X417200D01*
Y-1040000D01*
X420500D01*
X421200Y-1039467D01*
X421600Y-1038667D01*
X421800Y-1037733D01*
X421600Y-1036800D01*
X421000Y-1036000D01*
X420300Y-1035733D01*
X417200D01*
G01X427500Y-1040000D02*
Y-1032000D01*
X426300Y-1033600D01*
G01Y-1040000D02*
X428700D01*
G01X433000D02*
X435500Y-1032000D01*
X438000Y-1040000D01*
G01X437100Y-1037200D02*
X433900D01*
G01X441600Y-1040000D02*
Y-1032000D01*
X445400D01*
G01X444000Y-1035867D02*
X441600D01*
G01X451500Y-1032000D02*
X450700Y-1032267D01*
X450100Y-1032933D01*
X449700Y-1033733D01*
X449400Y-1034800D01*
X449300Y-1036000D01*
X449400Y-1037200D01*
X449700Y-1038267D01*
X450100Y-1039067D01*
X450700Y-1039733D01*
X451500Y-1040000D01*
X452300Y-1039733D01*
X452900Y-1039067D01*
X453300Y-1038267D01*
X453600Y-1037200D01*
X453700Y-1036000D01*
X453600Y-1034800D01*
X453300Y-1033733D01*
X452900Y-1032933D01*
X452300Y-1032267D01*
X451500Y-1032000D01*
G01X389600Y-1012500D02*
Y-1004500D01*
X393400D01*
G01X392000Y-1008367D02*
X389600D01*
G01X399500Y-1004500D02*
X398700Y-1004767D01*
X398100Y-1005433D01*
X397700Y-1006233D01*
X397400Y-1007300D01*
X397300Y-1008500D01*
X397400Y-1009700D01*
X397700Y-1010767D01*
X398100Y-1011567D01*
X398700Y-1012233D01*
X399500Y-1012500D01*
X400300Y-1012233D01*
X400900Y-1011567D01*
X401300Y-1010767D01*
X401600Y-1009700D01*
X401700Y-1008500D01*
X401600Y-1007300D01*
X401300Y-1006233D01*
X400900Y-1005433D01*
X400300Y-1004767D01*
X399500Y-1004500D01*
G01X407500D02*
Y-1012500D01*
G01X405200Y-1004500D02*
X409800D01*
G01X412500Y-1015167D02*
X418500D01*
G01X421500Y-1012500D02*
Y-1004500D01*
X423900D01*
X424700Y-1004900D01*
X425300Y-1005833D01*
X425500Y-1006900D01*
X425300Y-1007967D01*
X424800Y-1008767D01*
X423900Y-1009167D01*
X421500D01*
G01X429300Y-1012500D02*
Y-1004500D01*
X431300D01*
X432100Y-1004900D01*
X432700Y-1005433D01*
X433200Y-1006233D01*
X433600Y-1007167D01*
X433700Y-1008500D01*
X433600Y-1009833D01*
X433200Y-1010767D01*
X432700Y-1011567D01*
X432100Y-1012100D01*
X431300Y-1012500D01*
X429300D01*
G01X440300Y-1008233D02*
X440700Y-1007833D01*
X441000Y-1007167D01*
X441200Y-1006233D01*
X441000Y-1005433D01*
X440600Y-1004900D01*
X439900Y-1004500D01*
X437200D01*
Y-1012500D01*
X440500D01*
X441200Y-1011967D01*
X441600Y-1011167D01*
X441800Y-1010233D01*
X441600Y-1009300D01*
X441000Y-1008500D01*
X440300Y-1008233D01*
X437200D01*
G01X444500Y-1015167D02*
X450500D01*
G01X456300Y-1008233D02*
X456700Y-1007833D01*
X457000Y-1007167D01*
X457200Y-1006233D01*
X457000Y-1005433D01*
X456600Y-1004900D01*
X455900Y-1004500D01*
X453200D01*
Y-1012500D01*
X456500D01*
X457200Y-1011967D01*
X457600Y-1011167D01*
X457800Y-1010233D01*
X457600Y-1009300D01*
X457000Y-1008500D01*
X456300Y-1008233D01*
X453200D01*
G01X461300Y-1012500D02*
Y-1004500D01*
X463300D01*
X464100Y-1004900D01*
X464700Y-1005433D01*
X465200Y-1006233D01*
X465600Y-1007167D01*
X465700Y-1008500D01*
X465600Y-1009833D01*
X465200Y-1010767D01*
X464700Y-1011567D01*
X464100Y-1012100D01*
X463300Y-1012500D01*
X461300D01*
G01X468500Y-1015167D02*
X474500D01*
G01X480100Y-1008500D02*
X482100D01*
Y-1010900D01*
X481500Y-1011700D01*
X480800Y-1012233D01*
X479800Y-1012500D01*
X478800Y-1012233D01*
X478100Y-1011700D01*
X477500Y-1010900D01*
X477100Y-1009967D01*
X476900Y-1008900D01*
Y-1007967D01*
X477100Y-1007167D01*
X477500Y-1006233D01*
X478100Y-1005433D01*
X478700Y-1004900D01*
X479500Y-1004500D01*
X480200D01*
X481000Y-1004767D01*
X481600Y-1005300D01*
G01X485500Y-1012500D02*
Y-1004500D01*
X487900D01*
X488700Y-1004900D01*
X489300Y-1005833D01*
X489500Y-1006900D01*
X489300Y-1007967D01*
X488800Y-1008767D01*
X487900Y-1009167D01*
X485500D01*
G01X493300Y-1004500D02*
Y-1010233D01*
X493700Y-1011434D01*
X494500Y-1012233D01*
X495500Y-1012500D01*
X496500Y-1012233D01*
X497300Y-1011434D01*
X497700Y-1010233D01*
Y-1004500D01*
G01X458000Y-1065500D02*
Y-1057500D01*
X456800Y-1059100D01*
G01Y-1065500D02*
X459200D01*
G01X464100Y-1062167D02*
X464800Y-1061233D01*
X465400Y-1060700D01*
X466200Y-1060433D01*
X466900Y-1060700D01*
X467400Y-1061233D01*
X467800Y-1062033D01*
X467900Y-1062967D01*
X467800Y-1063767D01*
X467400Y-1064567D01*
X466800Y-1065233D01*
X466100Y-1065500D01*
X465300Y-1065233D01*
X464600Y-1064434D01*
X464200Y-1063233D01*
X464100Y-1061900D01*
X464300Y-1060167D01*
X464600Y-1059233D01*
X465100Y-1058300D01*
X465800Y-1057633D01*
X466500Y-1057500D01*
X467200Y-1057767D01*
X467700Y-1058433D01*
G01X474000Y-1065767D02*
X473800Y-1065633D01*
Y-1065367D01*
X474000Y-1065233D01*
X474200Y-1065367D01*
Y-1065633D01*
X474000Y-1065767D01*
G01X480100Y-1062167D02*
X480800Y-1061233D01*
X481400Y-1060700D01*
X482200Y-1060433D01*
X482900Y-1060700D01*
X483400Y-1061233D01*
X483800Y-1062033D01*
X483900Y-1062967D01*
X483800Y-1063767D01*
X483400Y-1064567D01*
X482800Y-1065233D01*
X482100Y-1065500D01*
X481300Y-1065233D01*
X480600Y-1064434D01*
X480200Y-1063233D01*
X480100Y-1061900D01*
X480300Y-1060167D01*
X480600Y-1059233D01*
X481100Y-1058300D01*
X481800Y-1057633D01*
X482500Y-1057500D01*
X483200Y-1057767D01*
X483700Y-1058433D01*
G01X503000Y-1065500D02*
Y-1057500D01*
X501800Y-1059100D01*
G01Y-1065500D02*
X504200D01*
G01X510800D02*
X511000Y-1063767D01*
X511300Y-1062300D01*
X511700Y-1060967D01*
X512200Y-1059500D01*
X513000Y-1057500D01*
X509000D01*
G01X519000Y-1065767D02*
X518800Y-1065633D01*
Y-1065367D01*
X519000Y-1065233D01*
X519200Y-1065367D01*
Y-1065633D01*
X519000Y-1065767D01*
G01X525100Y-1058833D02*
X525700Y-1058033D01*
X526400Y-1057633D01*
X527200Y-1057500D01*
X528200Y-1057767D01*
X528900Y-1058433D01*
X529100Y-1059233D01*
X529000Y-1060034D01*
X528600Y-1060700D01*
X526600Y-1062033D01*
X525700Y-1062967D01*
X525100Y-1064300D01*
X524900Y-1065500D01*
X529100D01*
G01X523100Y-1040500D02*
Y-1032500D01*
X526900D01*
G01X525500Y-1036367D02*
X523100D01*
M02*
